(kicad_sch (version 20230121) (generator eeschema)

  (paper "A3")

  (title_block
    (title "ECP5 - Datacenter Secure Control Module (DC-SCM)")
    (date "2024-07-15")
    (rev "1.2.1")
  )

  (junction (at 156.21 52.07) (diameter 0) (color 0 0 0 0)
  )
  (junction (at 154.94 63.5) (diameter 0) (color 0 0 0 0)
  )
  (junction (at 180.34 166.37) (diameter 0) (color 0 0 0 0)
  )
  (junction (at 274.32 48.26) (diameter 0) (color 0 0 0 0)
  )
  (junction (at 184.15 193.04) (diameter 0) (color 0 0 0 0)
  )
  (junction (at 116.84 73.66) (diameter 0) (color 0 0 0 0)
  )
  (junction (at 124.46 73.66) (diameter 0) (color 0 0 0 0)
  )
  (junction (at 242.57 219.71) (diameter 0) (color 0 0 0 0)
  )
  (junction (at 133.35 41.91) (diameter 0) (color 0 0 0 0)
  )
  (junction (at 139.7 63.5) (diameter 0) (color 0 0 0 0)
  )
  (junction (at 116.84 63.5) (diameter 0) (color 0 0 0 0)
  )
  (junction (at 148.59 223.52) (diameter 0) (color 0 0 0 0)
  )
  (junction (at 148.59 175.26) (diameter 0) (color 0 0 0 0)
  )
  (junction (at 140.97 41.91) (diameter 0) (color 0 0 0 0)
  )
  (junction (at 148.59 190.5) (diameter 0) (color 0 0 0 0)
  )
  (junction (at 148.59 52.07) (diameter 0) (color 0 0 0 0)
  )
  (junction (at 148.59 251.46) (diameter 0) (color 0 0 0 0)
  )
  (junction (at 195.58 179.07) (diameter 0) (color 0 0 0 0)
  )
  (junction (at 187.96 179.07) (diameter 0) (color 0 0 0 0)
  )
  (junction (at 132.08 63.5) (diameter 0) (color 0 0 0 0)
  )
  (junction (at 195.58 166.37) (diameter 0) (color 0 0 0 0)
  )
  (junction (at 234.95 48.26) (diameter 0) (color 0 0 0 0)
  )
  (junction (at 171.45 219.71) (diameter 0) (color 0 0 0 0)
  )
  (junction (at 148.59 177.8) (diameter 0) (color 0 0 0 0)
  )
  (junction (at 176.53 219.71) (diameter 0) (color 0 0 0 0)
  )
  (junction (at 148.59 220.98) (diameter 0) (color 0 0 0 0)
  )
  (junction (at 125.73 41.91) (diameter 0) (color 0 0 0 0)
  )
  (junction (at 194.31 247.65) (diameter 0) (color 0 0 0 0)
  )
  (junction (at 148.59 226.06) (diameter 0) (color 0 0 0 0)
  )
  (junction (at 148.59 185.42) (diameter 0) (color 0 0 0 0)
  )
  (junction (at 203.2 234.95) (diameter 0) (color 0 0 0 0)
  )
  (junction (at 140.97 52.07) (diameter 0) (color 0 0 0 0)
  )
  (junction (at 148.59 248.92) (diameter 0) (color 0 0 0 0)
  )
  (junction (at 125.73 52.07) (diameter 0) (color 0 0 0 0)
  )
  (junction (at 274.32 57.15) (diameter 0) (color 0 0 0 0)
  )
  (junction (at 148.59 180.34) (diameter 0) (color 0 0 0 0)
  )
  (junction (at 187.96 166.37) (diameter 0) (color 0 0 0 0)
  )
  (junction (at 148.59 210.82) (diameter 0) (color 0 0 0 0)
  )
  (junction (at 148.59 218.44) (diameter 0) (color 0 0 0 0)
  )
  (junction (at 147.32 63.5) (diameter 0) (color 0 0 0 0)
  )
  (junction (at 148.59 259.08) (diameter 0) (color 0 0 0 0)
  )
  (junction (at 132.08 73.66) (diameter 0) (color 0 0 0 0)
  )
  (junction (at 171.45 232.41) (diameter 0) (color 0 0 0 0)
  )
  (junction (at 148.59 182.88) (diameter 0) (color 0 0 0 0)
  )
  (junction (at 139.7 73.66) (diameter 0) (color 0 0 0 0)
  )
  (junction (at 148.59 187.96) (diameter 0) (color 0 0 0 0)
  )
  (junction (at 250.19 219.71) (diameter 0) (color 0 0 0 0)
  )
  (junction (at 116.84 41.91) (diameter 0) (color 0 0 0 0)
  )
  (junction (at 116.84 52.07) (diameter 0) (color 0 0 0 0)
  )
  (junction (at 124.46 63.5) (diameter 0) (color 0 0 0 0)
  )
  (junction (at 148.59 254) (diameter 0) (color 0 0 0 0)
  )
  (junction (at 148.59 213.36) (diameter 0) (color 0 0 0 0)
  )
  (junction (at 148.59 261.62) (diameter 0) (color 0 0 0 0)
  )
  (junction (at 148.59 256.54) (diameter 0) (color 0 0 0 0)
  )
  (junction (at 148.59 193.04) (diameter 0) (color 0 0 0 0)
  )
  (junction (at 265.43 48.26) (diameter 0) (color 0 0 0 0)
  )
  (junction (at 148.59 246.38) (diameter 0) (color 0 0 0 0)
  )
  (junction (at 133.35 52.07) (diameter 0) (color 0 0 0 0)
  )
  (junction (at 147.32 73.66) (diameter 0) (color 0 0 0 0)
  )
  (junction (at 148.59 228.6) (diameter 0) (color 0 0 0 0)
  )
  (junction (at 194.31 234.95) (diameter 0) (color 0 0 0 0)
  )
  (junction (at 156.21 41.91) (diameter 0) (color 0 0 0 0)
  )
  (junction (at 148.59 215.9) (diameter 0) (color 0 0 0 0)
  )
  (junction (at 133.35 107.95) (diameter 0) (color 0 0 0 0)
  )
  (junction (at 148.59 41.91) (diameter 0) (color 0 0 0 0)
  )
  (junction (at 242.57 231.14) (diameter 0) (color 0 0 0 0)
  )
  (junction (at 163.83 41.91) (diameter 0) (color 0 0 0 0)
  )

  (no_connect (at 232.41 110.49))
  (no_connect (at 232.41 118.11))
  (no_connect (at 232.41 113.03))
  (no_connect (at 232.41 115.57))
  (no_connect (at 232.41 120.65))

  (wire (pts (xy 186.69 91.44) (xy 196.85 91.44))
    (stroke (width 0) (type default))
  )
  (wire (pts (xy 148.59 190.5) (xy 138.43 190.5))
    (stroke (width 0) (type default))
  )
  (wire (pts (xy 242.57 231.14) (xy 250.19 231.14))
    (stroke (width 0) (type default))
  )
  (wire (pts (xy 171.45 227.33) (xy 171.45 232.41))
    (stroke (width 0) (type default))
  )
  (wire (pts (xy 186.69 132.08) (xy 196.85 132.08))
    (stroke (width 0) (type default))
  )
  (wire (pts (xy 186.69 116.84) (xy 196.85 116.84))
    (stroke (width 0) (type default))
  )
  (wire (pts (xy 170.18 63.5) (xy 154.94 63.5))
    (stroke (width 0) (type default))
  )
  (wire (pts (xy 171.45 232.41) (xy 171.45 234.95))
    (stroke (width 0) (type default))
  )
  (wire (pts (xy 242.57 213.36) (xy 229.87 213.36))
    (stroke (width 0) (type default))
  )
  (wire (pts (xy 195.58 166.37) (xy 195.58 170.18))
    (stroke (width 0) (type default))
  )
  (wire (pts (xy 148.59 185.42) (xy 138.43 185.42))
    (stroke (width 0) (type default))
  )
  (wire (pts (xy 139.7 73.66) (xy 147.32 73.66))
    (stroke (width 0) (type default))
  )
  (wire (pts (xy 186.69 83.82) (xy 196.85 83.82))
    (stroke (width 0) (type default))
  )
  (wire (pts (xy 138.43 228.6) (xy 148.59 228.6))
    (stroke (width 0) (type default))
  )
  (wire (pts (xy 187.96 175.26) (xy 187.96 179.07))
    (stroke (width 0) (type default))
  )
  (wire (pts (xy 148.59 246.38) (xy 138.43 246.38))
    (stroke (width 0) (type default))
  )
  (wire (pts (xy 148.59 254) (xy 138.43 254))
    (stroke (width 0) (type default))
  )
  (wire (pts (xy 171.45 217.17) (xy 171.45 219.71))
    (stroke (width 0) (type default))
  )
  (wire (pts (xy 251.46 219.71) (xy 250.19 219.71))
    (stroke (width 0) (type default))
  )
  (wire (pts (xy 171.45 219.71) (xy 176.53 219.71))
    (stroke (width 0) (type default))
  )
  (wire (pts (xy 139.7 71.12) (xy 139.7 73.66))
    (stroke (width 0) (type default))
  )
  (wire (pts (xy 186.69 121.92) (xy 196.85 121.92))
    (stroke (width 0) (type default))
  )
  (wire (pts (xy 116.84 52.07) (xy 125.73 52.07))
    (stroke (width 0) (type default))
  )
  (wire (pts (xy 123.19 256.54) (xy 128.27 256.54))
    (stroke (width 0) (type default))
  )
  (wire (pts (xy 187.96 166.37) (xy 187.96 170.18))
    (stroke (width 0) (type default))
  )
  (wire (pts (xy 148.59 193.04) (xy 148.59 210.82))
    (stroke (width 0) (type default))
  )
  (wire (pts (xy 151.13 110.49) (xy 151.13 107.95))
    (stroke (width 0) (type default))
  )
  (wire (pts (xy 148.59 175.26) (xy 148.59 177.8))
    (stroke (width 0) (type default))
  )
  (wire (pts (xy 148.59 185.42) (xy 148.59 187.96))
    (stroke (width 0) (type default))
  )
  (wire (pts (xy 148.59 166.37) (xy 180.34 166.37))
    (stroke (width 0) (type default))
  )
  (wire (pts (xy 148.59 180.34) (xy 148.59 182.88))
    (stroke (width 0) (type default))
  )
  (wire (pts (xy 186.69 104.14) (xy 196.85 104.14))
    (stroke (width 0) (type default))
  )
  (wire (pts (xy 186.69 114.3) (xy 196.85 114.3))
    (stroke (width 0) (type default))
  )
  (wire (pts (xy 123.19 185.42) (xy 128.27 185.42))
    (stroke (width 0) (type default))
  )
  (wire (pts (xy 186.69 129.54) (xy 196.85 129.54))
    (stroke (width 0) (type default))
  )
  (wire (pts (xy 195.58 179.07) (xy 187.96 179.07))
    (stroke (width 0) (type default))
  )
  (wire (pts (xy 250.19 228.6) (xy 250.19 231.14))
    (stroke (width 0) (type default))
  )
  (wire (pts (xy 110.49 41.91) (xy 116.84 41.91))
    (stroke (width 0) (type default))
  )
  (wire (pts (xy 125.73 41.91) (xy 133.35 41.91))
    (stroke (width 0) (type default))
  )
  (wire (pts (xy 123.19 218.44) (xy 128.27 218.44))
    (stroke (width 0) (type default))
  )
  (wire (pts (xy 148.59 226.06) (xy 138.43 226.06))
    (stroke (width 0) (type default))
  )
  (wire (pts (xy 116.84 41.91) (xy 116.84 44.45))
    (stroke (width 0) (type default))
  )
  (wire (pts (xy 242.57 58.42) (xy 232.41 58.42))
    (stroke (width 0) (type default))
  )
  (wire (pts (xy 148.59 261.62) (xy 148.59 259.08))
    (stroke (width 0) (type default))
  )
  (wire (pts (xy 186.69 127) (xy 196.85 127))
    (stroke (width 0) (type default))
  )
  (wire (pts (xy 148.59 182.88) (xy 148.59 185.42))
    (stroke (width 0) (type default))
  )
  (wire (pts (xy 148.59 41.91) (xy 156.21 41.91))
    (stroke (width 0) (type default))
  )
  (wire (pts (xy 129.54 116.84) (xy 133.35 116.84))
    (stroke (width 0) (type default))
  )
  (wire (pts (xy 148.59 52.07) (xy 156.21 52.07))
    (stroke (width 0) (type default))
  )
  (wire (pts (xy 125.73 49.53) (xy 125.73 52.07))
    (stroke (width 0) (type default))
  )
  (wire (pts (xy 186.69 96.52) (xy 196.85 96.52))
    (stroke (width 0) (type default))
  )
  (wire (pts (xy 123.19 175.26) (xy 128.27 175.26))
    (stroke (width 0) (type default))
  )
  (wire (pts (xy 265.43 48.26) (xy 265.43 49.53))
    (stroke (width 0) (type default))
  )
  (wire (pts (xy 139.7 63.5) (xy 147.32 63.5))
    (stroke (width 0) (type default))
  )
  (wire (pts (xy 250.19 219.71) (xy 242.57 219.71))
    (stroke (width 0) (type default))
  )
  (wire (pts (xy 234.95 134.62) (xy 232.41 134.62))
    (stroke (width 0) (type default))
  )
  (wire (pts (xy 234.95 48.26) (xy 234.95 50.8))
    (stroke (width 0) (type default))
  )
  (wire (pts (xy 123.19 259.08) (xy 128.27 259.08))
    (stroke (width 0) (type default))
  )
  (wire (pts (xy 186.69 60.96) (xy 196.85 60.96))
    (stroke (width 0) (type default))
  )
  (wire (pts (xy 186.69 63.5) (xy 196.85 63.5))
    (stroke (width 0) (type default))
  )
  (wire (pts (xy 234.95 134.62) (xy 234.95 139.7))
    (stroke (width 0) (type default))
  )
  (wire (pts (xy 133.35 49.53) (xy 133.35 52.07))
    (stroke (width 0) (type default))
  )
  (wire (pts (xy 116.84 71.12) (xy 116.84 73.66))
    (stroke (width 0) (type default))
  )
  (wire (pts (xy 186.69 66.04) (xy 196.85 66.04))
    (stroke (width 0) (type default))
  )
  (wire (pts (xy 138.43 218.44) (xy 148.59 218.44))
    (stroke (width 0) (type default))
  )
  (wire (pts (xy 265.43 48.26) (xy 274.32 48.26))
    (stroke (width 0) (type default))
  )
  (wire (pts (xy 116.84 73.66) (xy 124.46 73.66))
    (stroke (width 0) (type default))
  )
  (wire (pts (xy 133.35 41.91) (xy 140.97 41.91))
    (stroke (width 0) (type default))
  )
  (wire (pts (xy 242.57 86.36) (xy 232.41 86.36))
    (stroke (width 0) (type default))
  )
  (wire (pts (xy 250.19 219.71) (xy 250.19 223.52))
    (stroke (width 0) (type default))
  )
  (wire (pts (xy 187.96 179.07) (xy 180.34 179.07))
    (stroke (width 0) (type default))
  )
  (wire (pts (xy 242.57 60.96) (xy 232.41 60.96))
    (stroke (width 0) (type default))
  )
  (wire (pts (xy 195.58 179.07) (xy 195.58 180.34))
    (stroke (width 0) (type default))
  )
  (wire (pts (xy 156.21 41.91) (xy 163.83 41.91))
    (stroke (width 0) (type default))
  )
  (wire (pts (xy 184.15 193.04) (xy 207.01 193.04))
    (stroke (width 0) (type default))
  )
  (wire (pts (xy 171.45 219.71) (xy 171.45 222.25))
    (stroke (width 0) (type default))
  )
  (wire (pts (xy 148.59 190.5) (xy 148.59 193.04))
    (stroke (width 0) (type default))
  )
  (wire (pts (xy 186.69 86.36) (xy 196.85 86.36))
    (stroke (width 0) (type default))
  )
  (wire (pts (xy 148.59 215.9) (xy 148.59 218.44))
    (stroke (width 0) (type default))
  )
  (wire (pts (xy 123.19 193.04) (xy 128.27 193.04))
    (stroke (width 0) (type default))
  )
  (wire (pts (xy 184.15 193.04) (xy 180.34 193.04))
    (stroke (width 0) (type default))
  )
  (wire (pts (xy 123.19 223.52) (xy 128.27 223.52))
    (stroke (width 0) (type default))
  )
  (wire (pts (xy 138.43 182.88) (xy 148.59 182.88))
    (stroke (width 0) (type default))
  )
  (wire (pts (xy 184.15 199.39) (xy 184.15 200.66))
    (stroke (width 0) (type default))
  )
  (wire (pts (xy 180.34 166.37) (xy 187.96 166.37))
    (stroke (width 0) (type default))
  )
  (wire (pts (xy 196.85 76.2) (xy 186.69 76.2))
    (stroke (width 0) (type default))
  )
  (wire (pts (xy 278.13 48.26) (xy 274.32 48.26))
    (stroke (width 0) (type default))
  )
  (wire (pts (xy 138.43 180.34) (xy 148.59 180.34))
    (stroke (width 0) (type default))
  )
  (wire (pts (xy 186.69 93.98) (xy 196.85 93.98))
    (stroke (width 0) (type default))
  )
  (wire (pts (xy 148.59 261.62) (xy 148.59 264.16))
    (stroke (width 0) (type default))
  )
  (wire (pts (xy 242.57 81.28) (xy 232.41 81.28))
    (stroke (width 0) (type default))
  )
  (wire (pts (xy 148.59 259.08) (xy 148.59 256.54))
    (stroke (width 0) (type default))
  )
  (wire (pts (xy 138.43 220.98) (xy 148.59 220.98))
    (stroke (width 0) (type default))
  )
  (wire (pts (xy 186.69 55.88) (xy 196.85 55.88))
    (stroke (width 0) (type default))
  )
  (wire (pts (xy 204.47 222.25) (xy 209.55 222.25))
    (stroke (width 0) (type default))
  )
  (wire (pts (xy 176.53 219.71) (xy 209.55 219.71))
    (stroke (width 0) (type default))
  )
  (wire (pts (xy 147.32 63.5) (xy 154.94 63.5))
    (stroke (width 0) (type default))
  )
  (wire (pts (xy 171.45 208.28) (xy 171.45 212.09))
    (stroke (width 0) (type default))
  )
  (wire (pts (xy 191.77 48.26) (xy 191.77 41.91))
    (stroke (width 0) (type default))
  )
  (wire (pts (xy 123.19 187.96) (xy 128.27 187.96))
    (stroke (width 0) (type default))
  )
  (wire (pts (xy 138.43 256.54) (xy 148.59 256.54))
    (stroke (width 0) (type default))
  )
  (wire (pts (xy 195.58 175.26) (xy 195.58 179.07))
    (stroke (width 0) (type default))
  )
  (wire (pts (xy 140.97 52.07) (xy 148.59 52.07))
    (stroke (width 0) (type default))
  )
  (wire (pts (xy 242.57 78.74) (xy 232.41 78.74))
    (stroke (width 0) (type default))
  )
  (wire (pts (xy 274.32 48.26) (xy 274.32 49.53))
    (stroke (width 0) (type default))
  )
  (wire (pts (xy 148.59 41.91) (xy 148.59 44.45))
    (stroke (width 0) (type default))
  )
  (wire (pts (xy 148.59 223.52) (xy 148.59 226.06))
    (stroke (width 0) (type default))
  )
  (wire (pts (xy 242.57 228.6) (xy 242.57 231.14))
    (stroke (width 0) (type default))
  )
  (wire (pts (xy 232.41 132.08) (xy 238.76 132.08))
    (stroke (width 0) (type default))
  )
  (wire (pts (xy 156.21 41.91) (xy 156.21 44.45))
    (stroke (width 0) (type default))
  )
  (wire (pts (xy 116.84 63.5) (xy 124.46 63.5))
    (stroke (width 0) (type default))
  )
  (wire (pts (xy 180.34 166.37) (xy 180.34 170.18))
    (stroke (width 0) (type default))
  )
  (wire (pts (xy 147.32 73.66) (xy 154.94 73.66))
    (stroke (width 0) (type default))
  )
  (wire (pts (xy 186.69 109.22) (xy 196.85 109.22))
    (stroke (width 0) (type default))
  )
  (wire (pts (xy 242.57 76.2) (xy 232.41 76.2))
    (stroke (width 0) (type default))
  )
  (wire (pts (xy 156.21 52.07) (xy 163.83 52.07))
    (stroke (width 0) (type default))
  )
  (wire (pts (xy 138.43 259.08) (xy 148.59 259.08))
    (stroke (width 0) (type default))
  )
  (wire (pts (xy 128.27 210.82) (xy 123.19 210.82))
    (stroke (width 0) (type default))
  )
  (wire (pts (xy 147.32 63.5) (xy 147.32 66.04))
    (stroke (width 0) (type default))
  )
  (wire (pts (xy 242.57 232.41) (xy 242.57 231.14))
    (stroke (width 0) (type default))
  )
  (wire (pts (xy 138.43 213.36) (xy 148.59 213.36))
    (stroke (width 0) (type default))
  )
  (wire (pts (xy 116.84 63.5) (xy 116.84 66.04))
    (stroke (width 0) (type default))
  )
  (wire (pts (xy 128.27 180.34) (xy 123.19 180.34))
    (stroke (width 0) (type default))
  )
  (wire (pts (xy 207.01 210.82) (xy 209.55 210.82))
    (stroke (width 0) (type default))
  )
  (wire (pts (xy 148.59 215.9) (xy 138.43 215.9))
    (stroke (width 0) (type default))
  )
  (wire (pts (xy 140.97 41.91) (xy 148.59 41.91))
    (stroke (width 0) (type default))
  )
  (wire (pts (xy 148.59 246.38) (xy 148.59 248.92))
    (stroke (width 0) (type default))
  )
  (wire (pts (xy 138.43 248.92) (xy 148.59 248.92))
    (stroke (width 0) (type default))
  )
  (wire (pts (xy 242.57 219.71) (xy 242.57 223.52))
    (stroke (width 0) (type default))
  )
  (wire (pts (xy 128.27 246.38) (xy 123.19 246.38))
    (stroke (width 0) (type default))
  )
  (wire (pts (xy 138.43 187.96) (xy 148.59 187.96))
    (stroke (width 0) (type default))
  )
  (wire (pts (xy 148.59 251.46) (xy 148.59 254))
    (stroke (width 0) (type default))
  )
  (wire (pts (xy 242.57 91.44) (xy 232.41 91.44))
    (stroke (width 0) (type default))
  )
  (wire (pts (xy 123.19 228.6) (xy 128.27 228.6))
    (stroke (width 0) (type default))
  )
  (wire (pts (xy 123.19 177.8) (xy 128.27 177.8))
    (stroke (width 0) (type default))
  )
  (wire (pts (xy 200.66 213.36) (xy 196.85 213.36))
    (stroke (width 0) (type default))
  )
  (wire (pts (xy 242.57 104.14) (xy 232.41 104.14))
    (stroke (width 0) (type default))
  )
  (wire (pts (xy 156.21 49.53) (xy 156.21 52.07))
    (stroke (width 0) (type default))
  )
  (wire (pts (xy 138.43 175.26) (xy 148.59 175.26))
    (stroke (width 0) (type default))
  )
  (wire (pts (xy 242.57 101.6) (xy 232.41 101.6))
    (stroke (width 0) (type default))
  )
  (wire (pts (xy 186.69 134.62) (xy 196.85 134.62))
    (stroke (width 0) (type default))
  )
  (wire (pts (xy 265.43 57.15) (xy 274.32 57.15))
    (stroke (width 0) (type default))
  )
  (wire (pts (xy 133.35 107.95) (xy 142.24 107.95))
    (stroke (width 0) (type default))
  )
  (wire (pts (xy 196.85 50.8) (xy 170.18 50.8))
    (stroke (width 0) (type default))
  )
  (wire (pts (xy 274.32 54.61) (xy 274.32 57.15))
    (stroke (width 0) (type default))
  )
  (wire (pts (xy 123.19 215.9) (xy 128.27 215.9))
    (stroke (width 0) (type default))
  )
  (wire (pts (xy 274.32 57.15) (xy 274.32 58.42))
    (stroke (width 0) (type default))
  )
  (wire (pts (xy 139.7 63.5) (xy 139.7 66.04))
    (stroke (width 0) (type default))
  )
  (wire (pts (xy 132.08 63.5) (xy 132.08 66.04))
    (stroke (width 0) (type default))
  )
  (wire (pts (xy 180.34 175.26) (xy 180.34 179.07))
    (stroke (width 0) (type default))
  )
  (wire (pts (xy 243.84 132.08) (xy 243.84 139.7))
    (stroke (width 0) (type default))
  )
  (wire (pts (xy 140.97 41.91) (xy 140.97 44.45))
    (stroke (width 0) (type default))
  )
  (wire (pts (xy 133.35 105.41) (xy 133.35 107.95))
    (stroke (width 0) (type default))
  )
  (wire (pts (xy 234.95 48.26) (xy 265.43 48.26))
    (stroke (width 0) (type default))
  )
  (wire (pts (xy 128.27 213.36) (xy 123.19 213.36))
    (stroke (width 0) (type default))
  )
  (wire (pts (xy 184.15 193.04) (xy 184.15 194.31))
    (stroke (width 0) (type default))
  )
  (wire (pts (xy 148.59 175.26) (xy 148.59 166.37))
    (stroke (width 0) (type default))
  )
  (wire (pts (xy 148.59 187.96) (xy 148.59 190.5))
    (stroke (width 0) (type default))
  )
  (wire (pts (xy 186.69 119.38) (xy 196.85 119.38))
    (stroke (width 0) (type default))
  )
  (wire (pts (xy 194.31 247.65) (xy 203.2 247.65))
    (stroke (width 0) (type default))
  )
  (wire (pts (xy 194.31 234.95) (xy 203.2 234.95))
    (stroke (width 0) (type default))
  )
  (wire (pts (xy 147.32 107.95) (xy 151.13 107.95))
    (stroke (width 0) (type default))
  )
  (wire (pts (xy 116.84 41.91) (xy 125.73 41.91))
    (stroke (width 0) (type default))
  )
  (wire (pts (xy 148.59 220.98) (xy 148.59 223.52))
    (stroke (width 0) (type default))
  )
  (wire (pts (xy 133.35 52.07) (xy 140.97 52.07))
    (stroke (width 0) (type default))
  )
  (wire (pts (xy 148.59 218.44) (xy 148.59 220.98))
    (stroke (width 0) (type default))
  )
  (wire (pts (xy 125.73 52.07) (xy 133.35 52.07))
    (stroke (width 0) (type default))
  )
  (wire (pts (xy 204.47 222.25) (xy 204.47 234.95))
    (stroke (width 0) (type default))
  )
  (wire (pts (xy 132.08 71.12) (xy 132.08 73.66))
    (stroke (width 0) (type default))
  )
  (wire (pts (xy 242.57 93.98) (xy 232.41 93.98))
    (stroke (width 0) (type default))
  )
  (wire (pts (xy 133.35 99.06) (xy 129.54 99.06))
    (stroke (width 0) (type default))
  )
  (wire (pts (xy 148.59 261.62) (xy 138.43 261.62))
    (stroke (width 0) (type default))
  )
  (wire (pts (xy 207.01 193.04) (xy 207.01 210.82))
    (stroke (width 0) (type default))
  )
  (wire (pts (xy 123.19 251.46) (xy 128.27 251.46))
    (stroke (width 0) (type default))
  )
  (wire (pts (xy 171.45 232.41) (xy 176.53 232.41))
    (stroke (width 0) (type default))
  )
  (wire (pts (xy 148.59 210.82) (xy 148.59 213.36))
    (stroke (width 0) (type default))
  )
  (wire (pts (xy 201.93 215.9) (xy 209.55 215.9))
    (stroke (width 0) (type default))
  )
  (wire (pts (xy 148.59 177.8) (xy 148.59 180.34))
    (stroke (width 0) (type default))
  )
  (wire (pts (xy 242.57 88.9) (xy 232.41 88.9))
    (stroke (width 0) (type default))
  )
  (wire (pts (xy 186.69 111.76) (xy 196.85 111.76))
    (stroke (width 0) (type default))
  )
  (wire (pts (xy 233.68 166.37) (xy 233.68 210.82))
    (stroke (width 0) (type default))
  )
  (wire (pts (xy 123.19 190.5) (xy 128.27 190.5))
    (stroke (width 0) (type default))
  )
  (wire (pts (xy 133.35 115.57) (xy 133.35 116.84))
    (stroke (width 0) (type default))
  )
  (wire (pts (xy 123.19 264.16) (xy 128.27 264.16))
    (stroke (width 0) (type default))
  )
  (wire (pts (xy 148.59 228.6) (xy 148.59 246.38))
    (stroke (width 0) (type default))
  )
  (wire (pts (xy 187.96 166.37) (xy 195.58 166.37))
    (stroke (width 0) (type default))
  )
  (wire (pts (xy 123.19 182.88) (xy 128.27 182.88))
    (stroke (width 0) (type default))
  )
  (wire (pts (xy 128.27 254) (xy 123.19 254))
    (stroke (width 0) (type default))
  )
  (wire (pts (xy 203.2 234.95) (xy 203.2 238.76))
    (stroke (width 0) (type default))
  )
  (wire (pts (xy 132.08 73.66) (xy 139.7 73.66))
    (stroke (width 0) (type default))
  )
  (wire (pts (xy 242.57 96.52) (xy 232.41 96.52))
    (stroke (width 0) (type default))
  )
  (wire (pts (xy 186.69 71.12) (xy 196.85 71.12))
    (stroke (width 0) (type default))
  )
  (wire (pts (xy 170.18 50.8) (xy 170.18 63.5))
    (stroke (width 0) (type default))
  )
  (wire (pts (xy 186.69 99.06) (xy 196.85 99.06))
    (stroke (width 0) (type default))
  )
  (wire (pts (xy 132.08 63.5) (xy 139.7 63.5))
    (stroke (width 0) (type default))
  )
  (wire (pts (xy 233.68 210.82) (xy 229.87 210.82))
    (stroke (width 0) (type default))
  )
  (wire (pts (xy 148.59 226.06) (xy 148.59 228.6))
    (stroke (width 0) (type default))
  )
  (wire (pts (xy 133.35 99.06) (xy 133.35 100.33))
    (stroke (width 0) (type default))
  )
  (wire (pts (xy 238.76 132.08) (xy 238.76 139.7))
    (stroke (width 0) (type default))
  )
  (wire (pts (xy 196.85 48.26) (xy 191.77 48.26))
    (stroke (width 0) (type default))
  )
  (wire (pts (xy 116.84 49.53) (xy 116.84 52.07))
    (stroke (width 0) (type default))
  )
  (wire (pts (xy 163.83 41.91) (xy 163.83 44.45))
    (stroke (width 0) (type default))
  )
  (wire (pts (xy 186.69 58.42) (xy 196.85 58.42))
    (stroke (width 0) (type default))
  )
  (wire (pts (xy 203.2 243.84) (xy 203.2 247.65))
    (stroke (width 0) (type default))
  )
  (wire (pts (xy 194.31 247.65) (xy 194.31 250.19))
    (stroke (width 0) (type default))
  )
  (wire (pts (xy 138.43 193.04) (xy 148.59 193.04))
    (stroke (width 0) (type default))
  )
  (wire (pts (xy 186.69 73.66) (xy 196.85 73.66))
    (stroke (width 0) (type default))
  )
  (wire (pts (xy 123.19 248.92) (xy 128.27 248.92))
    (stroke (width 0) (type default))
  )
  (wire (pts (xy 138.43 177.8) (xy 148.59 177.8))
    (stroke (width 0) (type default))
  )
  (wire (pts (xy 186.69 106.68) (xy 196.85 106.68))
    (stroke (width 0) (type default))
  )
  (wire (pts (xy 154.94 63.5) (xy 154.94 66.04))
    (stroke (width 0) (type default))
  )
  (wire (pts (xy 148.59 213.36) (xy 148.59 215.9))
    (stroke (width 0) (type default))
  )
  (wire (pts (xy 229.87 232.41) (xy 229.87 222.25))
    (stroke (width 0) (type default))
  )
  (wire (pts (xy 138.43 251.46) (xy 148.59 251.46))
    (stroke (width 0) (type default))
  )
  (wire (pts (xy 176.53 219.71) (xy 176.53 222.25))
    (stroke (width 0) (type default))
  )
  (wire (pts (xy 116.84 52.07) (xy 116.84 54.61))
    (stroke (width 0) (type default))
  )
  (wire (pts (xy 148.59 49.53) (xy 148.59 52.07))
    (stroke (width 0) (type default))
  )
  (wire (pts (xy 128.27 261.62) (xy 123.19 261.62))
    (stroke (width 0) (type default))
  )
  (wire (pts (xy 163.83 49.53) (xy 163.83 52.07))
    (stroke (width 0) (type default))
  )
  (wire (pts (xy 148.59 256.54) (xy 148.59 254))
    (stroke (width 0) (type default))
  )
  (wire (pts (xy 186.69 101.6) (xy 196.85 101.6))
    (stroke (width 0) (type default))
  )
  (wire (pts (xy 242.57 99.06) (xy 232.41 99.06))
    (stroke (width 0) (type default))
  )
  (wire (pts (xy 242.57 83.82) (xy 232.41 83.82))
    (stroke (width 0) (type default))
  )
  (wire (pts (xy 242.57 71.12) (xy 232.41 71.12))
    (stroke (width 0) (type default))
  )
  (wire (pts (xy 242.57 73.66) (xy 232.41 73.66))
    (stroke (width 0) (type default))
  )
  (wire (pts (xy 232.41 68.58) (xy 242.57 68.58))
    (stroke (width 0) (type default))
  )
  (wire (pts (xy 205.74 213.36) (xy 209.55 213.36))
    (stroke (width 0) (type default))
  )
  (wire (pts (xy 148.59 210.82) (xy 138.43 210.82))
    (stroke (width 0) (type default))
  )
  (wire (pts (xy 124.46 63.5) (xy 124.46 66.04))
    (stroke (width 0) (type default))
  )
  (wire (pts (xy 148.59 248.92) (xy 148.59 251.46))
    (stroke (width 0) (type default))
  )
  (wire (pts (xy 232.41 50.8) (xy 234.95 50.8))
    (stroke (width 0) (type default))
  )
  (wire (pts (xy 194.31 234.95) (xy 190.5 234.95))
    (stroke (width 0) (type default))
  )
  (wire (pts (xy 232.41 124.46) (xy 243.84 124.46))
    (stroke (width 0) (type default))
  )
  (wire (pts (xy 116.84 76.2) (xy 116.84 73.66))
    (stroke (width 0) (type default))
  )
  (wire (pts (xy 186.69 81.28) (xy 196.85 81.28))
    (stroke (width 0) (type default))
  )
  (wire (pts (xy 133.35 107.95) (xy 133.35 110.49))
    (stroke (width 0) (type default))
  )
  (wire (pts (xy 124.46 63.5) (xy 132.08 63.5))
    (stroke (width 0) (type default))
  )
  (wire (pts (xy 242.57 63.5) (xy 232.41 63.5))
    (stroke (width 0) (type default))
  )
  (wire (pts (xy 194.31 243.84) (xy 194.31 247.65))
    (stroke (width 0) (type default))
  )
  (wire (pts (xy 110.49 63.5) (xy 116.84 63.5))
    (stroke (width 0) (type default))
  )
  (wire (pts (xy 154.94 71.12) (xy 154.94 73.66))
    (stroke (width 0) (type default))
  )
  (wire (pts (xy 243.84 124.46) (xy 243.84 127))
    (stroke (width 0) (type default))
  )
  (wire (pts (xy 133.35 41.91) (xy 133.35 44.45))
    (stroke (width 0) (type default))
  )
  (wire (pts (xy 125.73 41.91) (xy 125.73 44.45))
    (stroke (width 0) (type default))
  )
  (wire (pts (xy 191.77 41.91) (xy 163.83 41.91))
    (stroke (width 0) (type default))
  )
  (wire (pts (xy 176.53 227.33) (xy 176.53 232.41))
    (stroke (width 0) (type default))
  )
  (wire (pts (xy 232.41 48.26) (xy 234.95 48.26))
    (stroke (width 0) (type default))
  )
  (wire (pts (xy 186.69 124.46) (xy 196.85 124.46))
    (stroke (width 0) (type default))
  )
  (wire (pts (xy 138.43 223.52) (xy 148.59 223.52))
    (stroke (width 0) (type default))
  )
  (wire (pts (xy 138.43 264.16) (xy 148.59 264.16))
    (stroke (width 0) (type default))
  )
  (wire (pts (xy 128.27 220.98) (xy 123.19 220.98))
    (stroke (width 0) (type default))
  )
  (wire (pts (xy 229.87 219.71) (xy 242.57 219.71))
    (stroke (width 0) (type default))
  )
  (wire (pts (xy 123.19 226.06) (xy 128.27 226.06))
    (stroke (width 0) (type default))
  )
  (wire (pts (xy 242.57 55.88) (xy 232.41 55.88))
    (stroke (width 0) (type default))
  )
  (wire (pts (xy 194.31 234.95) (xy 194.31 238.76))
    (stroke (width 0) (type default))
  )
  (wire (pts (xy 171.45 208.28) (xy 170.18 208.28))
    (stroke (width 0) (type default))
  )
  (wire (pts (xy 204.47 234.95) (xy 203.2 234.95))
    (stroke (width 0) (type default))
  )
  (wire (pts (xy 140.97 49.53) (xy 140.97 52.07))
    (stroke (width 0) (type default))
  )
  (wire (pts (xy 242.57 106.68) (xy 232.41 106.68))
    (stroke (width 0) (type default))
  )
  (wire (pts (xy 147.32 71.12) (xy 147.32 73.66))
    (stroke (width 0) (type default))
  )
  (wire (pts (xy 124.46 73.66) (xy 132.08 73.66))
    (stroke (width 0) (type default))
  )
  (wire (pts (xy 124.46 71.12) (xy 124.46 73.66))
    (stroke (width 0) (type default))
  )
  (wire (pts (xy 195.58 166.37) (xy 233.68 166.37))
    (stroke (width 0) (type default))
  )
  (wire (pts (xy 265.43 54.61) (xy 265.43 57.15))
    (stroke (width 0) (type default))
  )

  (text "Source:Trellis board" (at 198.755 158.75 0)
    (effects (font (size 1.27 1.27)) (justify left bottom))
  )

  (label "DDR3_VTT" (at 242.57 213.36 180) (fields_autoplaced)
    (effects (font (size 1.27 1.27)) (justify right bottom))
  )
  (label "DDR3_VTT" (at 163.83 166.37 180) (fields_autoplaced)
    (effects (font (size 1.27 1.27)) (justify right bottom))
  )

  (global_label "DDR3_A2" (shape passive) (at 123.19 180.34 180) (fields_autoplaced)
    (effects (font (size 1.27 1.27)) (justify right))
    (property "Intersheetrefs" "${INTERSHEET_REFS}" (at 10.795 -12.065 0)
      (effects (font (size 1.27 1.27)) hide)
    )
  )
  (global_label "DDR3_DQ4" (shape bidirectional) (at 242.57 78.74 0) (fields_autoplaced)
    (effects (font (size 1.27 1.27)) (justify left))
    (property "Intersheetrefs" "${INTERSHEET_REFS}" (at 78.74 1.905 0)
      (effects (font (size 1.27 1.27)) hide)
    )
  )
  (global_label "DDR3_BA2" (shape passive) (at 123.19 248.92 180) (fields_autoplaced)
    (effects (font (size 1.27 1.27)) (justify right))
    (property "Intersheetrefs" "${INTERSHEET_REFS}" (at 10.795 -12.065 0)
      (effects (font (size 1.27 1.27)) hide)
    )
  )
  (global_label "DDR3_WE" (shape input) (at 186.69 63.5 180) (fields_autoplaced)
    (effects (font (size 1.27 1.27)) (justify right))
    (property "Intersheetrefs" "${INTERSHEET_REFS}" (at 93.98 -74.295 0)
      (effects (font (size 1.27 1.27)) hide)
    )
  )
  (global_label "DDR3_DQ12" (shape bidirectional) (at 242.57 99.06 0) (fields_autoplaced)
    (effects (font (size 1.27 1.27)) (justify left))
    (property "Intersheetrefs" "${INTERSHEET_REFS}" (at 78.74 1.905 0)
      (effects (font (size 1.27 1.27)) hide)
    )
  )
  (global_label "DDR3_DQ7" (shape bidirectional) (at 242.57 86.36 0) (fields_autoplaced)
    (effects (font (size 1.27 1.27)) (justify left))
    (property "Intersheetrefs" "${INTERSHEET_REFS}" (at 78.74 1.905 0)
      (effects (font (size 1.27 1.27)) hide)
    )
  )
  (global_label "DDR3_VTT_EN" (shape input) (at 201.93 215.9 180) (fields_autoplaced)
    (effects (font (size 1.27 1.27)) (justify right))
    (property "Intersheetrefs" "${INTERSHEET_REFS}" (at 417.83 -11.43 0)
      (effects (font (size 1.27 1.27)) hide)
    )
  )
  (global_label "DDR3_ODT" (shape input) (at 186.69 71.12 180) (fields_autoplaced)
    (effects (font (size 1.27 1.27)) (justify right))
    (property "Intersheetrefs" "${INTERSHEET_REFS}" (at 93.98 -69.215 0)
      (effects (font (size 1.27 1.27)) hide)
    )
  )
  (global_label "DDR3_VREF" (shape output) (at 251.46 219.71 0) (fields_autoplaced)
    (effects (font (size 1.27 1.27)) (justify left))
    (property "Intersheetrefs" "${INTERSHEET_REFS}" (at 427.355 -7.62 0)
      (effects (font (size 1.27 1.27)) hide)
    )
  )
  (global_label "DDR3_CS" (shape passive) (at 123.19 259.08 180) (fields_autoplaced)
    (effects (font (size 1.27 1.27)) (justify right))
    (property "Intersheetrefs" "${INTERSHEET_REFS}" (at 10.795 -12.065 0)
      (effects (font (size 1.27 1.27)) hide)
    )
  )
  (global_label "DDR3_DQS0+" (shape bidirectional) (at 242.57 55.88 0) (fields_autoplaced)
    (effects (font (size 1.27 1.27)) (justify left))
    (property "Intersheetrefs" "${INTERSHEET_REFS}" (at 78.74 -61.595 0)
      (effects (font (size 1.27 1.27)) hide)
    )
  )
  (global_label "DDR3_CKE" (shape passive) (at 123.19 228.6 180) (fields_autoplaced)
    (effects (font (size 1.27 1.27)) (justify right))
    (property "Intersheetrefs" "${INTERSHEET_REFS}" (at 10.795 -12.065 0)
      (effects (font (size 1.27 1.27)) hide)
    )
  )
  (global_label "DDR3_A10" (shape input) (at 186.69 116.84 180) (fields_autoplaced)
    (effects (font (size 1.27 1.27)) (justify right))
    (property "Intersheetrefs" "${INTERSHEET_REFS}" (at 93.98 24.765 0)
      (effects (font (size 1.27 1.27)) hide)
    )
  )
  (global_label "DDR3_A4" (shape passive) (at 123.19 215.9 180) (fields_autoplaced)
    (effects (font (size 1.27 1.27)) (justify right))
    (property "Intersheetrefs" "${INTERSHEET_REFS}" (at 10.795 -12.065 0)
      (effects (font (size 1.27 1.27)) hide)
    )
  )
  (global_label "DDR3_CLK-" (shape input) (at 186.69 86.36 180) (fields_autoplaced)
    (effects (font (size 1.27 1.27)) (justify right))
    (property "Intersheetrefs" "${INTERSHEET_REFS}" (at 93.98 -33.655 0)
      (effects (font (size 1.27 1.27)) hide)
    )
  )
  (global_label "DDR3_DQ2" (shape bidirectional) (at 242.57 73.66 0) (fields_autoplaced)
    (effects (font (size 1.27 1.27)) (justify left))
    (property "Intersheetrefs" "${INTERSHEET_REFS}" (at 78.74 1.905 0)
      (effects (font (size 1.27 1.27)) hide)
    )
  )
  (global_label "DDR3_VREF" (shape input) (at 278.13 48.26 0) (fields_autoplaced)
    (effects (font (size 1.27 1.27)) (justify left))
    (property "Intersheetrefs" "${INTERSHEET_REFS}" (at 291.0443 48.26 0)
      (effects (font (size 1.27 1.27)) (justify left) hide)
    )
  )
  (global_label "VCC3V3" (shape input) (at 196.85 213.36 180) (fields_autoplaced)
    (effects (font (size 1.27 1.27)) (justify right))
    (property "Intersheetrefs" "${INTERSHEET_REFS}" (at 22.225 10.16 0)
      (effects (font (size 1.27 1.27)) hide)
    )
  )
  (global_label "DDR3_DQ1" (shape bidirectional) (at 242.57 71.12 0) (fields_autoplaced)
    (effects (font (size 1.27 1.27)) (justify left))
    (property "Intersheetrefs" "${INTERSHEET_REFS}" (at 78.74 1.905 0)
      (effects (font (size 1.27 1.27)) hide)
    )
  )
  (global_label "DDR3_A14" (shape input) (at 186.69 127 180) (fields_autoplaced)
    (effects (font (size 1.27 1.27)) (justify right))
    (property "Intersheetrefs" "${INTERSHEET_REFS}" (at 93.98 24.765 0)
      (effects (font (size 1.27 1.27)) hide)
    )
  )
  (global_label "VCC1V35" (shape input) (at 190.5 234.95 180) (fields_autoplaced)
    (effects (font (size 1.27 1.27)) (justify right))
    (property "Intersheetrefs" "${INTERSHEET_REFS}" (at 415.925 56.515 0)
      (effects (font (size 1.27 1.27)) hide)
    )
  )
  (global_label "DDR3_A3" (shape input) (at 186.69 99.06 180) (fields_autoplaced)
    (effects (font (size 1.27 1.27)) (justify right))
    (property "Intersheetrefs" "${INTERSHEET_REFS}" (at 93.98 24.765 0)
      (effects (font (size 1.27 1.27)) hide)
    )
  )
  (global_label "DDR3_RESET" (shape input) (at 186.69 55.88 180) (fields_autoplaced)
    (effects (font (size 1.27 1.27)) (justify right))
    (property "Intersheetrefs" "${INTERSHEET_REFS}" (at 93.98 -71.755 0)
      (effects (font (size 1.27 1.27)) hide)
    )
  )
  (global_label "DDR3_BA1" (shape input) (at 186.69 132.08 180) (fields_autoplaced)
    (effects (font (size 1.27 1.27)) (justify right))
    (property "Intersheetrefs" "${INTERSHEET_REFS}" (at 93.98 22.225 0)
      (effects (font (size 1.27 1.27)) hide)
    )
  )
  (global_label "DDR3_DQS1+" (shape bidirectional) (at 242.57 60.96 0) (fields_autoplaced)
    (effects (font (size 1.27 1.27)) (justify left))
    (property "Intersheetrefs" "${INTERSHEET_REFS}" (at 78.74 -61.595 0)
      (effects (font (size 1.27 1.27)) hide)
    )
  )
  (global_label "DDR3_DQ3" (shape bidirectional) (at 242.57 76.2 0) (fields_autoplaced)
    (effects (font (size 1.27 1.27)) (justify left))
    (property "Intersheetrefs" "${INTERSHEET_REFS}" (at 78.74 1.905 0)
      (effects (font (size 1.27 1.27)) hide)
    )
  )
  (global_label "DDR3_A4" (shape input) (at 186.69 101.6 180) (fields_autoplaced)
    (effects (font (size 1.27 1.27)) (justify right))
    (property "Intersheetrefs" "${INTERSHEET_REFS}" (at 93.98 24.765 0)
      (effects (font (size 1.27 1.27)) hide)
    )
  )
  (global_label "DDR3_A8" (shape input) (at 186.69 111.76 180) (fields_autoplaced)
    (effects (font (size 1.27 1.27)) (justify right))
    (property "Intersheetrefs" "${INTERSHEET_REFS}" (at 93.98 24.765 0)
      (effects (font (size 1.27 1.27)) hide)
    )
  )
  (global_label "DDR3_A13" (shape input) (at 186.69 124.46 180) (fields_autoplaced)
    (effects (font (size 1.27 1.27)) (justify right))
    (property "Intersheetrefs" "${INTERSHEET_REFS}" (at 93.98 24.765 0)
      (effects (font (size 1.27 1.27)) hide)
    )
  )
  (global_label "DDR3_DQ0" (shape bidirectional) (at 242.57 68.58 0) (fields_autoplaced)
    (effects (font (size 1.27 1.27)) (justify left))
    (property "Intersheetrefs" "${INTERSHEET_REFS}" (at 78.74 1.905 0)
      (effects (font (size 1.27 1.27)) hide)
    )
  )
  (global_label "DDR3_DQS1-" (shape bidirectional) (at 242.57 63.5 0) (fields_autoplaced)
    (effects (font (size 1.27 1.27)) (justify left))
    (property "Intersheetrefs" "${INTERSHEET_REFS}" (at 78.74 -61.595 0)
      (effects (font (size 1.27 1.27)) hide)
    )
  )
  (global_label "DDR3_DQ10" (shape bidirectional) (at 242.57 93.98 0) (fields_autoplaced)
    (effects (font (size 1.27 1.27)) (justify left))
    (property "Intersheetrefs" "${INTERSHEET_REFS}" (at 78.74 1.905 0)
      (effects (font (size 1.27 1.27)) hide)
    )
  )
  (global_label "VCC1V35" (shape input) (at 170.18 208.28 180) (fields_autoplaced)
    (effects (font (size 1.27 1.27)) (justify right))
    (property "Intersheetrefs" "${INTERSHEET_REFS}" (at 13.335 5.08 0)
      (effects (font (size 1.27 1.27)) hide)
    )
  )
  (global_label "DDR3_CAS" (shape passive) (at 123.19 256.54 180) (fields_autoplaced)
    (effects (font (size 1.27 1.27)) (justify right))
    (property "Intersheetrefs" "${INTERSHEET_REFS}" (at 10.795 -12.065 0)
      (effects (font (size 1.27 1.27)) hide)
    )
  )
  (global_label "DDR3_A2" (shape input) (at 186.69 96.52 180) (fields_autoplaced)
    (effects (font (size 1.27 1.27)) (justify right))
    (property "Intersheetrefs" "${INTERSHEET_REFS}" (at 93.98 24.765 0)
      (effects (font (size 1.27 1.27)) hide)
    )
  )
  (global_label "DDR3_DQ9" (shape bidirectional) (at 242.57 91.44 0) (fields_autoplaced)
    (effects (font (size 1.27 1.27)) (justify left))
    (property "Intersheetrefs" "${INTERSHEET_REFS}" (at 78.74 1.905 0)
      (effects (font (size 1.27 1.27)) hide)
    )
  )
  (global_label "DDR3_A14" (shape passive) (at 123.19 193.04 180) (fields_autoplaced)
    (effects (font (size 1.27 1.27)) (justify right))
    (property "Intersheetrefs" "${INTERSHEET_REFS}" (at 10.795 -12.065 0)
      (effects (font (size 1.27 1.27)) hide)
    )
  )
  (global_label "DDR3_DM1" (shape bidirectional) (at 186.69 76.2 180) (fields_autoplaced)
    (effects (font (size 1.27 1.27)) (justify right))
    (property "Intersheetrefs" "${INTERSHEET_REFS}" (at 350.52 -36.195 0)
      (effects (font (size 1.27 1.27)) hide)
    )
  )
  (global_label "DDR3_DQ11" (shape bidirectional) (at 242.57 96.52 0) (fields_autoplaced)
    (effects (font (size 1.27 1.27)) (justify left))
    (property "Intersheetrefs" "${INTERSHEET_REFS}" (at 78.74 1.905 0)
      (effects (font (size 1.27 1.27)) hide)
    )
  )
  (global_label "DDR3_CAS" (shape input) (at 186.69 60.96 180) (fields_autoplaced)
    (effects (font (size 1.27 1.27)) (justify right))
    (property "Intersheetrefs" "${INTERSHEET_REFS}" (at 93.98 -74.295 0)
      (effects (font (size 1.27 1.27)) hide)
    )
  )
  (global_label "DDR3_A8" (shape passive) (at 123.19 210.82 180) (fields_autoplaced)
    (effects (font (size 1.27 1.27)) (justify right))
    (property "Intersheetrefs" "${INTERSHEET_REFS}" (at 10.795 -12.065 0)
      (effects (font (size 1.27 1.27)) hide)
    )
  )
  (global_label "DDR3_ODT" (shape passive) (at 123.19 264.16 180) (fields_autoplaced)
    (effects (font (size 1.27 1.27)) (justify right))
    (property "Intersheetrefs" "${INTERSHEET_REFS}" (at 10.795 -12.065 0)
      (effects (font (size 1.27 1.27)) hide)
    )
  )
  (global_label "DDR3_DM0" (shape bidirectional) (at 186.69 73.66 180) (fields_autoplaced)
    (effects (font (size 1.27 1.27)) (justify right))
    (property "Intersheetrefs" "${INTERSHEET_REFS}" (at 350.52 -36.195 0)
      (effects (font (size 1.27 1.27)) hide)
    )
  )
  (global_label "DDR3_CS" (shape input) (at 186.69 66.04 180) (fields_autoplaced)
    (effects (font (size 1.27 1.27)) (justify right))
    (property "Intersheetrefs" "${INTERSHEET_REFS}" (at 93.98 -64.135 0)
      (effects (font (size 1.27 1.27)) hide)
    )
  )
  (global_label "DDR3_A11" (shape input) (at 186.69 119.38 180) (fields_autoplaced)
    (effects (font (size 1.27 1.27)) (justify right))
    (property "Intersheetrefs" "${INTERSHEET_REFS}" (at 93.98 24.765 0)
      (effects (font (size 1.27 1.27)) hide)
    )
  )
  (global_label "DDR3_A7" (shape input) (at 186.69 109.22 180) (fields_autoplaced)
    (effects (font (size 1.27 1.27)) (justify right))
    (property "Intersheetrefs" "${INTERSHEET_REFS}" (at 93.98 24.765 0)
      (effects (font (size 1.27 1.27)) hide)
    )
  )
  (global_label "DDR3_A5" (shape input) (at 186.69 104.14 180) (fields_autoplaced)
    (effects (font (size 1.27 1.27)) (justify right))
    (property "Intersheetrefs" "${INTERSHEET_REFS}" (at 93.98 24.765 0)
      (effects (font (size 1.27 1.27)) hide)
    )
  )
  (global_label "DDR3_BA2" (shape input) (at 186.69 134.62 180) (fields_autoplaced)
    (effects (font (size 1.27 1.27)) (justify right))
    (property "Intersheetrefs" "${INTERSHEET_REFS}" (at 93.98 22.225 0)
      (effects (font (size 1.27 1.27)) hide)
    )
  )
  (global_label "DDR3_A11" (shape passive) (at 123.19 190.5 180) (fields_autoplaced)
    (effects (font (size 1.27 1.27)) (justify right))
    (property "Intersheetrefs" "${INTERSHEET_REFS}" (at 10.795 -12.065 0)
      (effects (font (size 1.27 1.27)) hide)
    )
  )
  (global_label "DDR3_DQ13" (shape bidirectional) (at 242.57 101.6 0) (fields_autoplaced)
    (effects (font (size 1.27 1.27)) (justify left))
    (property "Intersheetrefs" "${INTERSHEET_REFS}" (at 78.74 1.905 0)
      (effects (font (size 1.27 1.27)) hide)
    )
  )
  (global_label "VCC1V35" (shape input) (at 110.49 63.5 180) (fields_autoplaced)
    (effects (font (size 1.27 1.27)) (justify right))
    (property "Intersheetrefs" "${INTERSHEET_REFS}" (at -186.69 3.175 0)
      (effects (font (size 1.27 1.27)) hide)
    )
  )
  (global_label "DDR3_BA0" (shape input) (at 186.69 129.54 180) (fields_autoplaced)
    (effects (font (size 1.27 1.27)) (justify right))
    (property "Intersheetrefs" "${INTERSHEET_REFS}" (at 93.98 22.225 0)
      (effects (font (size 1.27 1.27)) hide)
    )
  )
  (global_label "DDR3_BA0" (shape passive) (at 123.19 261.62 180) (fields_autoplaced)
    (effects (font (size 1.27 1.27)) (justify right))
    (property "Intersheetrefs" "${INTERSHEET_REFS}" (at 10.795 -12.065 0)
      (effects (font (size 1.27 1.27)) hide)
    )
  )
  (global_label "DDR3_A10" (shape passive) (at 123.19 226.06 180) (fields_autoplaced)
    (effects (font (size 1.27 1.27)) (justify right))
    (property "Intersheetrefs" "${INTERSHEET_REFS}" (at 10.795 -12.065 0)
      (effects (font (size 1.27 1.27)) hide)
    )
  )
  (global_label "DDR3_CKE" (shape input) (at 186.69 81.28 180) (fields_autoplaced)
    (effects (font (size 1.27 1.27)) (justify right))
    (property "Intersheetrefs" "${INTERSHEET_REFS}" (at 93.98 -41.275 0)
      (effects (font (size 1.27 1.27)) hide)
    )
  )
  (global_label "DDR3_A1" (shape passive) (at 123.19 218.44 180) (fields_autoplaced)
    (effects (font (size 1.27 1.27)) (justify right))
    (property "Intersheetrefs" "${INTERSHEET_REFS}" (at 10.795 -12.065 0)
      (effects (font (size 1.27 1.27)) hide)
    )
  )
  (global_label "DDR3_A0" (shape input) (at 186.69 91.44 180) (fields_autoplaced)
    (effects (font (size 1.27 1.27)) (justify right))
    (property "Intersheetrefs" "${INTERSHEET_REFS}" (at 93.98 24.765 0)
      (effects (font (size 1.27 1.27)) hide)
    )
  )
  (global_label "DDR3_DQ15" (shape bidirectional) (at 242.57 106.68 0) (fields_autoplaced)
    (effects (font (size 1.27 1.27)) (justify left))
    (property "Intersheetrefs" "${INTERSHEET_REFS}" (at 78.74 1.905 0)
      (effects (font (size 1.27 1.27)) hide)
    )
  )
  (global_label "DDR3_DQ5" (shape bidirectional) (at 242.57 81.28 0) (fields_autoplaced)
    (effects (font (size 1.27 1.27)) (justify left))
    (property "Intersheetrefs" "${INTERSHEET_REFS}" (at 78.74 1.905 0)
      (effects (font (size 1.27 1.27)) hide)
    )
  )
  (global_label "DDR3_A3" (shape passive) (at 123.19 177.8 180) (fields_autoplaced)
    (effects (font (size 1.27 1.27)) (justify right))
    (property "Intersheetrefs" "${INTERSHEET_REFS}" (at 10.795 -12.065 0)
      (effects (font (size 1.27 1.27)) hide)
    )
  )
  (global_label "DDR3_DQ8" (shape bidirectional) (at 242.57 88.9 0) (fields_autoplaced)
    (effects (font (size 1.27 1.27)) (justify left))
    (property "Intersheetrefs" "${INTERSHEET_REFS}" (at 78.74 1.905 0)
      (effects (font (size 1.27 1.27)) hide)
    )
  )
  (global_label "DDR3_A5" (shape passive) (at 123.19 182.88 180) (fields_autoplaced)
    (effects (font (size 1.27 1.27)) (justify right))
    (property "Intersheetrefs" "${INTERSHEET_REFS}" (at 10.795 -12.065 0)
      (effects (font (size 1.27 1.27)) hide)
    )
  )
  (global_label "DDR3_DQ14" (shape bidirectional) (at 242.57 104.14 0) (fields_autoplaced)
    (effects (font (size 1.27 1.27)) (justify left))
    (property "Intersheetrefs" "${INTERSHEET_REFS}" (at 78.74 1.905 0)
      (effects (font (size 1.27 1.27)) hide)
    )
  )
  (global_label "DDR3_BA1" (shape passive) (at 123.19 223.52 180) (fields_autoplaced)
    (effects (font (size 1.27 1.27)) (justify right))
    (property "Intersheetrefs" "${INTERSHEET_REFS}" (at 10.795 -12.065 0)
      (effects (font (size 1.27 1.27)) hide)
    )
  )
  (global_label "DDR3_A6" (shape input) (at 186.69 106.68 180) (fields_autoplaced)
    (effects (font (size 1.27 1.27)) (justify right))
    (property "Intersheetrefs" "${INTERSHEET_REFS}" (at 93.98 24.765 0)
      (effects (font (size 1.27 1.27)) hide)
    )
  )
  (global_label "DDR3_CLK+" (shape input) (at 186.69 83.82 180) (fields_autoplaced)
    (effects (font (size 1.27 1.27)) (justify right))
    (property "Intersheetrefs" "${INTERSHEET_REFS}" (at 93.98 -33.655 0)
      (effects (font (size 1.27 1.27)) hide)
    )
  )
  (global_label "DDR3_A6" (shape passive) (at 123.19 213.36 180) (fields_autoplaced)
    (effects (font (size 1.27 1.27)) (justify right))
    (property "Intersheetrefs" "${INTERSHEET_REFS}" (at 10.795 -12.065 0)
      (effects (font (size 1.27 1.27)) hide)
    )
  )
  (global_label "DDR3_RAS" (shape passive) (at 123.19 254 180) (fields_autoplaced)
    (effects (font (size 1.27 1.27)) (justify right))
    (property "Intersheetrefs" "${INTERSHEET_REFS}" (at 10.795 -12.065 0)
      (effects (font (size 1.27 1.27)) hide)
    )
  )
  (global_label "VCC3V3" (shape input) (at 180.34 193.04 180) (fields_autoplaced)
    (effects (font (size 1.27 1.27)) (justify right))
    (property "Intersheetrefs" "${INTERSHEET_REFS}" (at 417.195 -15.24 0)
      (effects (font (size 1.27 1.27)) hide)
    )
  )
  (global_label "DDR3_A0" (shape passive) (at 123.19 246.38 180) (fields_autoplaced)
    (effects (font (size 1.27 1.27)) (justify right))
    (property "Intersheetrefs" "${INTERSHEET_REFS}" (at 10.795 -12.065 0)
      (effects (font (size 1.27 1.27)) hide)
    )
  )
  (global_label "DDR3_A12" (shape input) (at 186.69 121.92 180) (fields_autoplaced)
    (effects (font (size 1.27 1.27)) (justify right))
    (property "Intersheetrefs" "${INTERSHEET_REFS}" (at 93.98 24.765 0)
      (effects (font (size 1.27 1.27)) hide)
    )
  )
  (global_label "DDR3_A1" (shape input) (at 186.69 93.98 180) (fields_autoplaced)
    (effects (font (size 1.27 1.27)) (justify right))
    (property "Intersheetrefs" "${INTERSHEET_REFS}" (at 93.98 24.765 0)
      (effects (font (size 1.27 1.27)) hide)
    )
  )
  (global_label "DDR3_A12" (shape passive) (at 123.19 220.98 180) (fields_autoplaced)
    (effects (font (size 1.27 1.27)) (justify right))
    (property "Intersheetrefs" "${INTERSHEET_REFS}" (at 10.795 -12.065 0)
      (effects (font (size 1.27 1.27)) hide)
    )
  )
  (global_label "DDR3_A13" (shape passive) (at 123.19 187.96 180) (fields_autoplaced)
    (effects (font (size 1.27 1.27)) (justify right))
    (property "Intersheetrefs" "${INTERSHEET_REFS}" (at 10.795 -12.065 0)
      (effects (font (size 1.27 1.27)) hide)
    )
  )
  (global_label "DDR3_A7" (shape passive) (at 123.19 175.26 180) (fields_autoplaced)
    (effects (font (size 1.27 1.27)) (justify right))
    (property "Intersheetrefs" "${INTERSHEET_REFS}" (at 10.795 -12.065 0)
      (effects (font (size 1.27 1.27)) hide)
    )
  )
  (global_label "DDR3_DQS0-" (shape bidirectional) (at 242.57 58.42 0) (fields_autoplaced)
    (effects (font (size 1.27 1.27)) (justify left))
    (property "Intersheetrefs" "${INTERSHEET_REFS}" (at 78.74 -61.595 0)
      (effects (font (size 1.27 1.27)) hide)
    )
  )
  (global_label "DDR3_CLK-" (shape input) (at 129.54 116.84 180) (fields_autoplaced)
    (effects (font (size 1.27 1.27)) (justify right))
    (property "Intersheetrefs" "${INTERSHEET_REFS}" (at -205.105 -90.805 0)
      (effects (font (size 1.27 1.27)) hide)
    )
  )
  (global_label "DDR3_CLK+" (shape input) (at 129.54 99.06 180) (fields_autoplaced)
    (effects (font (size 1.27 1.27)) (justify right))
    (property "Intersheetrefs" "${INTERSHEET_REFS}" (at -205.105 -90.805 0)
      (effects (font (size 1.27 1.27)) hide)
    )
  )
  (global_label "DDR3_WE" (shape passive) (at 123.19 251.46 180) (fields_autoplaced)
    (effects (font (size 1.27 1.27)) (justify right))
    (property "Intersheetrefs" "${INTERSHEET_REFS}" (at 10.795 -12.065 0)
      (effects (font (size 1.27 1.27)) hide)
    )
  )
  (global_label "DDR3_A9" (shape input) (at 186.69 114.3 180) (fields_autoplaced)
    (effects (font (size 1.27 1.27)) (justify right))
    (property "Intersheetrefs" "${INTERSHEET_REFS}" (at 93.98 24.765 0)
      (effects (font (size 1.27 1.27)) hide)
    )
  )
  (global_label "DDR3_A9" (shape passive) (at 123.19 185.42 180) (fields_autoplaced)
    (effects (font (size 1.27 1.27)) (justify right))
    (property "Intersheetrefs" "${INTERSHEET_REFS}" (at 10.795 -12.065 0)
      (effects (font (size 1.27 1.27)) hide)
    )
  )
  (global_label "DDR3_RAS" (shape input) (at 186.69 58.42 180) (fields_autoplaced)
    (effects (font (size 1.27 1.27)) (justify right))
    (property "Intersheetrefs" "${INTERSHEET_REFS}" (at 93.98 -74.295 0)
      (effects (font (size 1.27 1.27)) hide)
    )
  )
  (global_label "DDR3_DQ6" (shape bidirectional) (at 242.57 83.82 0) (fields_autoplaced)
    (effects (font (size 1.27 1.27)) (justify left))
    (property "Intersheetrefs" "${INTERSHEET_REFS}" (at 78.74 1.905 0)
      (effects (font (size 1.27 1.27)) hide)
    )
  )
  (global_label "VCC1V35" (shape input) (at 110.49 41.91 180) (fields_autoplaced)
    (effects (font (size 1.27 1.27)) (justify right))
    (property "Intersheetrefs" "${INTERSHEET_REFS}" (at -186.69 -18.415 0)
      (effects (font (size 1.27 1.27)) hide)
    )
  )

  (symbol (lib_id "antmicroResistors0402:R_51R_0402") (at 133.35 100.33 270) (unit 1)
    (in_bom yes) (on_board yes) (dnp no)
    (property "Reference" "R82" (at 134.62 101.6 90)
      (effects (font (size 1.524 1.524)) (justify left))
    )
    (property "Value" "R_51R_0402" (at 129.54 100.33 0)
      (effects (font (size 1.524 1.524)) hide)
    )
    (property "Footprint" "antmicro-footprints:R_0402_1005Metric" (at 138.43 105.41 0)
      (effects (font (size 1.524 1.524)) (justify left) hide)
    )
    (property "Datasheet" "https://www.bourns.com/docs/product-datasheets/cr.pdf" (at 133.35 100.33 0)
      (effects (font (size 1.27 1.27)) hide)
    )
    (property "Manufacturer" "Bourns" (at 143.51 105.41 0)
      (effects (font (size 1.524 1.524)) (justify left) hide)
    )
    (property "MPN" "CR0402-FX-51R0GLF" (at 140.97 105.41 0)
      (effects (font (size 1.524 1.524)) (justify left) hide)
    )
    (property "Val" "51R" (at 134.62 104.0892 90)
      (effects (font (size 1.27 1.27)) (justify left))
    )
    (property "License" "Apache-2.0" (at 107.95 120.65 0)
      (effects (font (size 1.27 1.27) (thickness 0.15)) (justify left bottom) hide)
    )
    (property "Author" "Antmicro" (at 105.41 120.65 0)
      (effects (font (size 1.27 1.27) (thickness 0.15)) (justify left bottom) hide)
    )
    (property "Tolerance" "1%" (at 123.19 120.65 0)
      (effects (font (size 1.27 1.27)) (justify left bottom) hide)
    )
    (property "Public" "False" (at 102.87 120.65 0)
      (effects (font (size 1.27 1.27)) (justify left bottom) hide)
    )
    (pin "1")
    (pin "2")
    (instances
      (project "ecp5-dc-scm"
        (path ""
          (reference "R82") (unit 1)
        )
      )
    )
  )

  (symbol (lib_id "antmicroResistors0402:R_51R_0402") (at 133.35 110.49 270) (unit 1)
    (in_bom yes) (on_board yes) (dnp no)
    (property "Reference" "R83" (at 134.62 111.76 90)
      (effects (font (size 1.524 1.524)) (justify left))
    )
    (property "Value" "R_51R_0402" (at 129.54 110.49 0)
      (effects (font (size 1.524 1.524)) hide)
    )
    (property "Footprint" "antmicro-footprints:R_0402_1005Metric" (at 138.43 115.57 0)
      (effects (font (size 1.524 1.524)) (justify left) hide)
    )
    (property "Datasheet" "https://www.bourns.com/docs/product-datasheets/cr.pdf" (at 133.35 110.49 0)
      (effects (font (size 1.27 1.27)) hide)
    )
    (property "Manufacturer" "Bourns" (at 143.51 115.57 0)
      (effects (font (size 1.524 1.524)) (justify left) hide)
    )
    (property "MPN" "CR0402-FX-51R0GLF" (at 140.97 115.57 0)
      (effects (font (size 1.524 1.524)) (justify left) hide)
    )
    (property "Val" "51R" (at 134.62 114.2492 90)
      (effects (font (size 1.27 1.27)) (justify left))
    )
    (property "License" "Apache-2.0" (at 107.95 130.81 0)
      (effects (font (size 1.27 1.27) (thickness 0.15)) (justify left bottom) hide)
    )
    (property "Author" "Antmicro" (at 105.41 130.81 0)
      (effects (font (size 1.27 1.27) (thickness 0.15)) (justify left bottom) hide)
    )
    (property "Tolerance" "1%" (at 123.19 130.81 0)
      (effects (font (size 1.27 1.27)) (justify left bottom) hide)
    )
    (property "Public" "False" (at 102.87 130.81 0)
      (effects (font (size 1.27 1.27)) (justify left bottom) hide)
    )
    (pin "1")
    (pin "2")
    (instances
      (project "ecp5-dc-scm"
        (path ""
          (reference "R83") (unit 1)
        )
      )
    )
  )

  (symbol (lib_id "antmicroCapacitors0402:C_4u7_0402") (at 116.84 49.53 90) (unit 1)
    (in_bom yes) (on_board yes) (dnp no)
    (property "Reference" "C79" (at 114.3 48.895 0)
      (effects (font (size 1.524 1.524)) (justify left))
    )
    (property "Value" "C_4u7_0402" (at 120.65 49.53 0)
      (effects (font (size 1.524 1.524)) hide)
    )
    (property "Footprint" "antmicro-footprints:C_0402_1005Metric" (at 111.76 44.45 0)
      (effects (font (size 1.524 1.524)) (justify left) hide)
    )
    (property "Datasheet" "https://www.murata.com/products/productdetail?partno=GRM155R61A475MEAA%23" (at 116.84 49.53 0)
      (effects (font (size 1.27 1.27)) hide)
    )
    (property "Manufacturer" "Murata" (at 106.68 44.45 0)
      (effects (font (size 1.524 1.524)) (justify left) hide)
    )
    (property "MPN" "GRM155R61A475MEAAD" (at 109.22 44.45 0)
      (effects (font (size 1.524 1.524)) (justify left) hide)
    )
    (property "Val" "4u7" (at 119.38 48.895 0)
      (effects (font (size 1.27 1.27)) (justify left))
    )
    (property "License" "Apache-2.0" (at 139.7 29.21 0)
      (effects (font (size 1.27 1.27) (thickness 0.15)) (justify left bottom) hide)
    )
    (property "Author" "Antmicro" (at 142.24 29.21 0)
      (effects (font (size 1.27 1.27) (thickness 0.15)) (justify left bottom) hide)
    )
    (property "Voltage" "" (at 144.78 29.21 0)
      (effects (font (size 1.27 1.27)) (justify left bottom) hide)
    )
    (property "Dielectric" "" (at 147.32 29.21 0)
      (effects (font (size 1.27 1.27)) (justify left bottom) hide)
    )
    (property "Public" "False" (at 149.86 29.21 0)
      (effects (font (size 1.27 1.27)) (justify left bottom) hide)
    )
    (pin "1")
    (pin "2")
    (instances
      (project "ecp5-dc-scm"
        (path ""
          (reference "C79") (unit 1)
        )
      )
    )
  )

  (symbol (lib_id "antmicroCapacitors0402:C_470n_0402") (at 125.73 49.53 90) (unit 1)
    (in_bom yes) (on_board yes) (dnp no)
    (property "Reference" "C80" (at 123.19 48.895 0)
      (effects (font (size 1.524 1.524)) (justify left))
    )
    (property "Value" "C_470n_0402" (at 129.54 49.53 0)
      (effects (font (size 1.524 1.524)) hide)
    )
    (property "Footprint" "antmicro-footprints:C_0402_1005Metric" (at 120.65 44.45 0)
      (effects (font (size 1.524 1.524)) (justify left) hide)
    )
    (property "Datasheet" "https://product.tdk.com/en/search/capacitor/ceramic/mlcc/info?part_no=C1005X5R1E474M050BB" (at 125.73 49.53 0)
      (effects (font (size 1.27 1.27)) hide)
    )
    (property "Manufacturer" "TDK" (at 115.57 44.45 0)
      (effects (font (size 1.524 1.524)) (justify left) hide)
    )
    (property "MPN" "C1005X5R1E474M050BB" (at 118.11 44.45 0)
      (effects (font (size 1.524 1.524)) (justify left) hide)
    )
    (property "Val" "470n" (at 128.27 48.895 0)
      (effects (font (size 1.27 1.27)) (justify left))
    )
    (property "License" "Apache-2.0" (at 148.59 29.21 0)
      (effects (font (size 1.27 1.27) (thickness 0.15)) (justify left bottom) hide)
    )
    (property "Author" "Antmicro" (at 151.13 29.21 0)
      (effects (font (size 1.27 1.27) (thickness 0.15)) (justify left bottom) hide)
    )
    (property "Voltage" "" (at 153.67 29.21 0)
      (effects (font (size 1.27 1.27)) (justify left bottom) hide)
    )
    (property "Dielectric" "" (at 156.21 29.21 0)
      (effects (font (size 1.27 1.27)) (justify left bottom) hide)
    )
    (property "Public" "False" (at 158.75 29.21 0)
      (effects (font (size 1.27 1.27)) (justify left bottom) hide)
    )
    (pin "1")
    (pin "2")
    (instances
      (project "ecp5-dc-scm"
        (path ""
          (reference "C80") (unit 1)
        )
      )
    )
  )

  (symbol (lib_id "antmicroCapacitors0402:C_470n_0402") (at 133.35 49.53 90) (unit 1)
    (in_bom yes) (on_board yes) (dnp no)
    (property "Reference" "C82" (at 130.81 48.895 0)
      (effects (font (size 1.524 1.524)) (justify left))
    )
    (property "Value" "C_470n_0402" (at 137.16 49.53 0)
      (effects (font (size 1.524 1.524)) hide)
    )
    (property "Footprint" "antmicro-footprints:C_0402_1005Metric" (at 128.27 44.45 0)
      (effects (font (size 1.524 1.524)) (justify left) hide)
    )
    (property "Datasheet" "https://product.tdk.com/en/search/capacitor/ceramic/mlcc/info?part_no=C1005X5R1E474M050BB" (at 133.35 49.53 0)
      (effects (font (size 1.27 1.27)) hide)
    )
    (property "Manufacturer" "TDK" (at 123.19 44.45 0)
      (effects (font (size 1.524 1.524)) (justify left) hide)
    )
    (property "MPN" "C1005X5R1E474M050BB" (at 125.73 44.45 0)
      (effects (font (size 1.524 1.524)) (justify left) hide)
    )
    (property "Val" "470n" (at 135.89 48.895 0)
      (effects (font (size 1.27 1.27)) (justify left))
    )
    (property "License" "Apache-2.0" (at 156.21 29.21 0)
      (effects (font (size 1.27 1.27) (thickness 0.15)) (justify left bottom) hide)
    )
    (property "Author" "Antmicro" (at 158.75 29.21 0)
      (effects (font (size 1.27 1.27) (thickness 0.15)) (justify left bottom) hide)
    )
    (property "Voltage" "" (at 161.29 29.21 0)
      (effects (font (size 1.27 1.27)) (justify left bottom) hide)
    )
    (property "Dielectric" "" (at 163.83 29.21 0)
      (effects (font (size 1.27 1.27)) (justify left bottom) hide)
    )
    (property "Public" "False" (at 166.37 29.21 0)
      (effects (font (size 1.27 1.27)) (justify left bottom) hide)
    )
    (pin "1")
    (pin "2")
    (instances
      (project "ecp5-dc-scm"
        (path ""
          (reference "C82") (unit 1)
        )
      )
    )
  )

  (symbol (lib_id "antmicroCapacitors0402:C_470n_0402") (at 140.97 49.53 90) (unit 1)
    (in_bom yes) (on_board yes) (dnp no)
    (property "Reference" "C84" (at 138.43 48.895 0)
      (effects (font (size 1.524 1.524)) (justify left))
    )
    (property "Value" "C_470n_0402" (at 144.78 49.53 0)
      (effects (font (size 1.524 1.524)) hide)
    )
    (property "Footprint" "antmicro-footprints:C_0402_1005Metric" (at 135.89 44.45 0)
      (effects (font (size 1.524 1.524)) (justify left) hide)
    )
    (property "Datasheet" "https://product.tdk.com/en/search/capacitor/ceramic/mlcc/info?part_no=C1005X5R1E474M050BB" (at 140.97 49.53 0)
      (effects (font (size 1.27 1.27)) hide)
    )
    (property "Manufacturer" "TDK" (at 130.81 44.45 0)
      (effects (font (size 1.524 1.524)) (justify left) hide)
    )
    (property "MPN" "C1005X5R1E474M050BB" (at 133.35 44.45 0)
      (effects (font (size 1.524 1.524)) (justify left) hide)
    )
    (property "Val" "470n" (at 143.51 48.895 0)
      (effects (font (size 1.27 1.27)) (justify left))
    )
    (property "License" "Apache-2.0" (at 163.83 29.21 0)
      (effects (font (size 1.27 1.27) (thickness 0.15)) (justify left bottom) hide)
    )
    (property "Author" "Antmicro" (at 166.37 29.21 0)
      (effects (font (size 1.27 1.27) (thickness 0.15)) (justify left bottom) hide)
    )
    (property "Voltage" "" (at 168.91 29.21 0)
      (effects (font (size 1.27 1.27)) (justify left bottom) hide)
    )
    (property "Dielectric" "" (at 171.45 29.21 0)
      (effects (font (size 1.27 1.27)) (justify left bottom) hide)
    )
    (property "Public" "False" (at 173.99 29.21 0)
      (effects (font (size 1.27 1.27)) (justify left bottom) hide)
    )
    (pin "1")
    (pin "2")
    (instances
      (project "ecp5-dc-scm"
        (path ""
          (reference "C84") (unit 1)
        )
      )
    )
  )

  (symbol (lib_id "antmicroCapacitors0402:C_470n_0402") (at 148.59 49.53 90) (unit 1)
    (in_bom yes) (on_board yes) (dnp no)
    (property "Reference" "C86" (at 146.05 48.895 0)
      (effects (font (size 1.524 1.524)) (justify left))
    )
    (property "Value" "C_470n_0402" (at 152.4 49.53 0)
      (effects (font (size 1.524 1.524)) hide)
    )
    (property "Footprint" "antmicro-footprints:C_0402_1005Metric" (at 143.51 44.45 0)
      (effects (font (size 1.524 1.524)) (justify left) hide)
    )
    (property "Datasheet" "https://product.tdk.com/en/search/capacitor/ceramic/mlcc/info?part_no=C1005X5R1E474M050BB" (at 148.59 49.53 0)
      (effects (font (size 1.27 1.27)) hide)
    )
    (property "Manufacturer" "TDK" (at 138.43 44.45 0)
      (effects (font (size 1.524 1.524)) (justify left) hide)
    )
    (property "MPN" "C1005X5R1E474M050BB" (at 140.97 44.45 0)
      (effects (font (size 1.524 1.524)) (justify left) hide)
    )
    (property "Val" "470n" (at 151.13 48.895 0)
      (effects (font (size 1.27 1.27)) (justify left))
    )
    (property "License" "Apache-2.0" (at 171.45 29.21 0)
      (effects (font (size 1.27 1.27) (thickness 0.15)) (justify left bottom) hide)
    )
    (property "Author" "Antmicro" (at 173.99 29.21 0)
      (effects (font (size 1.27 1.27) (thickness 0.15)) (justify left bottom) hide)
    )
    (property "Voltage" "" (at 176.53 29.21 0)
      (effects (font (size 1.27 1.27)) (justify left bottom) hide)
    )
    (property "Dielectric" "" (at 179.07 29.21 0)
      (effects (font (size 1.27 1.27)) (justify left bottom) hide)
    )
    (property "Public" "False" (at 181.61 29.21 0)
      (effects (font (size 1.27 1.27)) (justify left bottom) hide)
    )
    (pin "1")
    (pin "2")
    (instances
      (project "ecp5-dc-scm"
        (path ""
          (reference "C86") (unit 1)
        )
      )
    )
  )

  (symbol (lib_id "antmicroCapacitors0402:C_470n_0402") (at 156.21 49.53 90) (unit 1)
    (in_bom yes) (on_board yes) (dnp no)
    (property "Reference" "C89" (at 153.67 48.895 0)
      (effects (font (size 1.524 1.524)) (justify left))
    )
    (property "Value" "C_470n_0402" (at 160.02 49.53 0)
      (effects (font (size 1.524 1.524)) hide)
    )
    (property "Footprint" "antmicro-footprints:C_0402_1005Metric" (at 151.13 44.45 0)
      (effects (font (size 1.524 1.524)) (justify left) hide)
    )
    (property "Datasheet" "https://product.tdk.com/en/search/capacitor/ceramic/mlcc/info?part_no=C1005X5R1E474M050BB" (at 156.21 49.53 0)
      (effects (font (size 1.27 1.27)) hide)
    )
    (property "Manufacturer" "TDK" (at 146.05 44.45 0)
      (effects (font (size 1.524 1.524)) (justify left) hide)
    )
    (property "MPN" "C1005X5R1E474M050BB" (at 148.59 44.45 0)
      (effects (font (size 1.524 1.524)) (justify left) hide)
    )
    (property "Val" "470n" (at 158.75 48.895 0)
      (effects (font (size 1.27 1.27)) (justify left))
    )
    (property "License" "Apache-2.0" (at 179.07 29.21 0)
      (effects (font (size 1.27 1.27) (thickness 0.15)) (justify left bottom) hide)
    )
    (property "Author" "Antmicro" (at 181.61 29.21 0)
      (effects (font (size 1.27 1.27) (thickness 0.15)) (justify left bottom) hide)
    )
    (property "Voltage" "" (at 184.15 29.21 0)
      (effects (font (size 1.27 1.27)) (justify left bottom) hide)
    )
    (property "Dielectric" "" (at 186.69 29.21 0)
      (effects (font (size 1.27 1.27)) (justify left bottom) hide)
    )
    (property "Public" "False" (at 189.23 29.21 0)
      (effects (font (size 1.27 1.27)) (justify left bottom) hide)
    )
    (pin "1")
    (pin "2")
    (instances
      (project "ecp5-dc-scm"
        (path ""
          (reference "C89") (unit 1)
        )
      )
    )
  )

  (symbol (lib_id "antmicroCapacitors0402:C_470n_0402") (at 163.83 49.53 90) (unit 1)
    (in_bom yes) (on_board yes) (dnp no)
    (property "Reference" "C91" (at 161.29 48.895 0)
      (effects (font (size 1.524 1.524)) (justify left))
    )
    (property "Value" "C_470n_0402" (at 167.64 49.53 0)
      (effects (font (size 1.524 1.524)) hide)
    )
    (property "Footprint" "antmicro-footprints:C_0402_1005Metric" (at 158.75 44.45 0)
      (effects (font (size 1.524 1.524)) (justify left) hide)
    )
    (property "Datasheet" "https://product.tdk.com/en/search/capacitor/ceramic/mlcc/info?part_no=C1005X5R1E474M050BB" (at 163.83 49.53 0)
      (effects (font (size 1.27 1.27)) hide)
    )
    (property "Manufacturer" "TDK" (at 153.67 44.45 0)
      (effects (font (size 1.524 1.524)) (justify left) hide)
    )
    (property "MPN" "C1005X5R1E474M050BB" (at 156.21 44.45 0)
      (effects (font (size 1.524 1.524)) (justify left) hide)
    )
    (property "Val" "470n" (at 166.37 48.895 0)
      (effects (font (size 1.27 1.27)) (justify left))
    )
    (property "License" "Apache-2.0" (at 186.69 29.21 0)
      (effects (font (size 1.27 1.27) (thickness 0.15)) (justify left bottom) hide)
    )
    (property "Author" "Antmicro" (at 189.23 29.21 0)
      (effects (font (size 1.27 1.27) (thickness 0.15)) (justify left bottom) hide)
    )
    (property "Voltage" "" (at 191.77 29.21 0)
      (effects (font (size 1.27 1.27)) (justify left bottom) hide)
    )
    (property "Dielectric" "" (at 194.31 29.21 0)
      (effects (font (size 1.27 1.27)) (justify left bottom) hide)
    )
    (property "Public" "False" (at 196.85 29.21 0)
      (effects (font (size 1.27 1.27)) (justify left bottom) hide)
    )
    (pin "1")
    (pin "2")
    (instances
      (project "ecp5-dc-scm"
        (path ""
          (reference "C91") (unit 1)
        )
      )
    )
  )

  (symbol (lib_id "antmicroCapacitors0402:C_470n_0402") (at 116.84 71.12 90) (unit 1)
    (in_bom yes) (on_board yes) (dnp no)
    (property "Reference" "C81" (at 114.3 70.485 0)
      (effects (font (size 1.524 1.524)) (justify left))
    )
    (property "Value" "C_470n_0402" (at 120.65 71.12 0)
      (effects (font (size 1.524 1.524)) hide)
    )
    (property "Footprint" "antmicro-footprints:C_0402_1005Metric" (at 111.76 66.04 0)
      (effects (font (size 1.524 1.524)) (justify left) hide)
    )
    (property "Datasheet" "https://product.tdk.com/en/search/capacitor/ceramic/mlcc/info?part_no=C1005X5R1E474M050BB" (at 116.84 71.12 0)
      (effects (font (size 1.27 1.27)) hide)
    )
    (property "Manufacturer" "TDK" (at 106.68 66.04 0)
      (effects (font (size 1.524 1.524)) (justify left) hide)
    )
    (property "MPN" "C1005X5R1E474M050BB" (at 109.22 66.04 0)
      (effects (font (size 1.524 1.524)) (justify left) hide)
    )
    (property "Val" "470n" (at 119.38 70.485 0)
      (effects (font (size 1.27 1.27)) (justify left))
    )
    (property "License" "Apache-2.0" (at 139.7 50.8 0)
      (effects (font (size 1.27 1.27) (thickness 0.15)) (justify left bottom) hide)
    )
    (property "Author" "Antmicro" (at 142.24 50.8 0)
      (effects (font (size 1.27 1.27) (thickness 0.15)) (justify left bottom) hide)
    )
    (property "Voltage" "" (at 144.78 50.8 0)
      (effects (font (size 1.27 1.27)) (justify left bottom) hide)
    )
    (property "Dielectric" "" (at 147.32 50.8 0)
      (effects (font (size 1.27 1.27)) (justify left bottom) hide)
    )
    (property "Public" "False" (at 149.86 50.8 0)
      (effects (font (size 1.27 1.27)) (justify left bottom) hide)
    )
    (pin "1")
    (pin "2")
    (instances
      (project "ecp5-dc-scm"
        (path ""
          (reference "C81") (unit 1)
        )
      )
    )
  )

  (symbol (lib_id "antmicroCapacitors0402:C_470n_0402") (at 124.46 71.12 90) (unit 1)
    (in_bom yes) (on_board yes) (dnp no)
    (property "Reference" "C83" (at 121.92 70.485 0)
      (effects (font (size 1.524 1.524)) (justify left))
    )
    (property "Value" "C_470n_0402" (at 128.27 71.12 0)
      (effects (font (size 1.524 1.524)) hide)
    )
    (property "Footprint" "antmicro-footprints:C_0402_1005Metric" (at 119.38 66.04 0)
      (effects (font (size 1.524 1.524)) (justify left) hide)
    )
    (property "Datasheet" "https://product.tdk.com/en/search/capacitor/ceramic/mlcc/info?part_no=C1005X5R1E474M050BB" (at 124.46 71.12 0)
      (effects (font (size 1.27 1.27)) hide)
    )
    (property "Manufacturer" "TDK" (at 114.3 66.04 0)
      (effects (font (size 1.524 1.524)) (justify left) hide)
    )
    (property "MPN" "C1005X5R1E474M050BB" (at 116.84 66.04 0)
      (effects (font (size 1.524 1.524)) (justify left) hide)
    )
    (property "Val" "470n" (at 127 70.485 0)
      (effects (font (size 1.27 1.27)) (justify left))
    )
    (property "License" "Apache-2.0" (at 147.32 50.8 0)
      (effects (font (size 1.27 1.27) (thickness 0.15)) (justify left bottom) hide)
    )
    (property "Author" "Antmicro" (at 149.86 50.8 0)
      (effects (font (size 1.27 1.27) (thickness 0.15)) (justify left bottom) hide)
    )
    (property "Voltage" "" (at 152.4 50.8 0)
      (effects (font (size 1.27 1.27)) (justify left bottom) hide)
    )
    (property "Dielectric" "" (at 154.94 50.8 0)
      (effects (font (size 1.27 1.27)) (justify left bottom) hide)
    )
    (property "Public" "False" (at 157.48 50.8 0)
      (effects (font (size 1.27 1.27)) (justify left bottom) hide)
    )
    (pin "1")
    (pin "2")
    (instances
      (project "ecp5-dc-scm"
        (path ""
          (reference "C83") (unit 1)
        )
      )
    )
  )

  (symbol (lib_id "antmicroCapacitors0402:C_470n_0402") (at 132.08 71.12 90) (unit 1)
    (in_bom yes) (on_board yes) (dnp no)
    (property "Reference" "C85" (at 129.54 70.485 0)
      (effects (font (size 1.524 1.524)) (justify left))
    )
    (property "Value" "C_470n_0402" (at 135.89 71.12 0)
      (effects (font (size 1.524 1.524)) hide)
    )
    (property "Footprint" "antmicro-footprints:C_0402_1005Metric" (at 127 66.04 0)
      (effects (font (size 1.524 1.524)) (justify left) hide)
    )
    (property "Datasheet" "https://product.tdk.com/en/search/capacitor/ceramic/mlcc/info?part_no=C1005X5R1E474M050BB" (at 132.08 71.12 0)
      (effects (font (size 1.27 1.27)) hide)
    )
    (property "Manufacturer" "TDK" (at 121.92 66.04 0)
      (effects (font (size 1.524 1.524)) (justify left) hide)
    )
    (property "MPN" "C1005X5R1E474M050BB" (at 124.46 66.04 0)
      (effects (font (size 1.524 1.524)) (justify left) hide)
    )
    (property "Val" "470n" (at 134.62 70.485 0)
      (effects (font (size 1.27 1.27)) (justify left))
    )
    (property "License" "Apache-2.0" (at 154.94 50.8 0)
      (effects (font (size 1.27 1.27) (thickness 0.15)) (justify left bottom) hide)
    )
    (property "Author" "Antmicro" (at 157.48 50.8 0)
      (effects (font (size 1.27 1.27) (thickness 0.15)) (justify left bottom) hide)
    )
    (property "Voltage" "" (at 160.02 50.8 0)
      (effects (font (size 1.27 1.27)) (justify left bottom) hide)
    )
    (property "Dielectric" "" (at 162.56 50.8 0)
      (effects (font (size 1.27 1.27)) (justify left bottom) hide)
    )
    (property "Public" "False" (at 165.1 50.8 0)
      (effects (font (size 1.27 1.27)) (justify left bottom) hide)
    )
    (pin "1")
    (pin "2")
    (instances
      (project "ecp5-dc-scm"
        (path ""
          (reference "C85") (unit 1)
        )
      )
    )
  )

  (symbol (lib_id "antmicroCapacitors0402:C_470n_0402") (at 139.7 71.12 90) (unit 1)
    (in_bom yes) (on_board yes) (dnp no)
    (property "Reference" "C87" (at 137.16 70.485 0)
      (effects (font (size 1.524 1.524)) (justify left))
    )
    (property "Value" "C_470n_0402" (at 143.51 71.12 0)
      (effects (font (size 1.524 1.524)) hide)
    )
    (property "Footprint" "antmicro-footprints:C_0402_1005Metric" (at 134.62 66.04 0)
      (effects (font (size 1.524 1.524)) (justify left) hide)
    )
    (property "Datasheet" "https://product.tdk.com/en/search/capacitor/ceramic/mlcc/info?part_no=C1005X5R1E474M050BB" (at 139.7 71.12 0)
      (effects (font (size 1.27 1.27)) hide)
    )
    (property "Manufacturer" "TDK" (at 129.54 66.04 0)
      (effects (font (size 1.524 1.524)) (justify left) hide)
    )
    (property "MPN" "C1005X5R1E474M050BB" (at 132.08 66.04 0)
      (effects (font (size 1.524 1.524)) (justify left) hide)
    )
    (property "Val" "470n" (at 142.24 70.485 0)
      (effects (font (size 1.27 1.27)) (justify left))
    )
    (property "License" "Apache-2.0" (at 162.56 50.8 0)
      (effects (font (size 1.27 1.27) (thickness 0.15)) (justify left bottom) hide)
    )
    (property "Author" "Antmicro" (at 165.1 50.8 0)
      (effects (font (size 1.27 1.27) (thickness 0.15)) (justify left bottom) hide)
    )
    (property "Voltage" "" (at 167.64 50.8 0)
      (effects (font (size 1.27 1.27)) (justify left bottom) hide)
    )
    (property "Dielectric" "" (at 170.18 50.8 0)
      (effects (font (size 1.27 1.27)) (justify left bottom) hide)
    )
    (property "Public" "False" (at 172.72 50.8 0)
      (effects (font (size 1.27 1.27)) (justify left bottom) hide)
    )
    (pin "1")
    (pin "2")
    (instances
      (project "ecp5-dc-scm"
        (path ""
          (reference "C87") (unit 1)
        )
      )
    )
  )

  (symbol (lib_id "antmicroCapacitors0402:C_470n_0402") (at 147.32 71.12 90) (unit 1)
    (in_bom yes) (on_board yes) (dnp no)
    (property "Reference" "C90" (at 144.78 70.485 0)
      (effects (font (size 1.524 1.524)) (justify left))
    )
    (property "Value" "C_470n_0402" (at 151.13 71.12 0)
      (effects (font (size 1.524 1.524)) hide)
    )
    (property "Footprint" "antmicro-footprints:C_0402_1005Metric" (at 142.24 66.04 0)
      (effects (font (size 1.524 1.524)) (justify left) hide)
    )
    (property "Datasheet" "https://product.tdk.com/en/search/capacitor/ceramic/mlcc/info?part_no=C1005X5R1E474M050BB" (at 147.32 71.12 0)
      (effects (font (size 1.27 1.27)) hide)
    )
    (property "Manufacturer" "TDK" (at 137.16 66.04 0)
      (effects (font (size 1.524 1.524)) (justify left) hide)
    )
    (property "MPN" "C1005X5R1E474M050BB" (at 139.7 66.04 0)
      (effects (font (size 1.524 1.524)) (justify left) hide)
    )
    (property "Val" "470n" (at 149.86 70.485 0)
      (effects (font (size 1.27 1.27)) (justify left))
    )
    (property "License" "Apache-2.0" (at 170.18 50.8 0)
      (effects (font (size 1.27 1.27) (thickness 0.15)) (justify left bottom) hide)
    )
    (property "Author" "Antmicro" (at 172.72 50.8 0)
      (effects (font (size 1.27 1.27) (thickness 0.15)) (justify left bottom) hide)
    )
    (property "Voltage" "" (at 175.26 50.8 0)
      (effects (font (size 1.27 1.27)) (justify left bottom) hide)
    )
    (property "Dielectric" "" (at 177.8 50.8 0)
      (effects (font (size 1.27 1.27)) (justify left bottom) hide)
    )
    (property "Public" "False" (at 180.34 50.8 0)
      (effects (font (size 1.27 1.27)) (justify left bottom) hide)
    )
    (pin "1")
    (pin "2")
    (instances
      (project "ecp5-dc-scm"
        (path ""
          (reference "C90") (unit 1)
        )
      )
    )
  )

  (symbol (lib_id "antmicroCapacitors0402:C_470n_0402") (at 154.94 71.12 90) (unit 1)
    (in_bom yes) (on_board yes) (dnp no)
    (property "Reference" "C92" (at 152.4 70.485 0)
      (effects (font (size 1.524 1.524)) (justify left))
    )
    (property "Value" "C_470n_0402" (at 158.75 71.12 0)
      (effects (font (size 1.524 1.524)) hide)
    )
    (property "Footprint" "antmicro-footprints:C_0402_1005Metric" (at 149.86 66.04 0)
      (effects (font (size 1.524 1.524)) (justify left) hide)
    )
    (property "Datasheet" "https://product.tdk.com/en/search/capacitor/ceramic/mlcc/info?part_no=C1005X5R1E474M050BB" (at 154.94 71.12 0)
      (effects (font (size 1.27 1.27)) hide)
    )
    (property "Manufacturer" "TDK" (at 144.78 66.04 0)
      (effects (font (size 1.524 1.524)) (justify left) hide)
    )
    (property "MPN" "C1005X5R1E474M050BB" (at 147.32 66.04 0)
      (effects (font (size 1.524 1.524)) (justify left) hide)
    )
    (property "Val" "470n" (at 157.48 70.485 0)
      (effects (font (size 1.27 1.27)) (justify left))
    )
    (property "License" "Apache-2.0" (at 177.8 50.8 0)
      (effects (font (size 1.27 1.27) (thickness 0.15)) (justify left bottom) hide)
    )
    (property "Author" "Antmicro" (at 180.34 50.8 0)
      (effects (font (size 1.27 1.27) (thickness 0.15)) (justify left bottom) hide)
    )
    (property "Voltage" "" (at 182.88 50.8 0)
      (effects (font (size 1.27 1.27)) (justify left bottom) hide)
    )
    (property "Dielectric" "" (at 185.42 50.8 0)
      (effects (font (size 1.27 1.27)) (justify left bottom) hide)
    )
    (property "Public" "False" (at 187.96 50.8 0)
      (effects (font (size 1.27 1.27)) (justify left bottom) hide)
    )
    (pin "1")
    (pin "2")
    (instances
      (project "ecp5-dc-scm"
        (path ""
          (reference "C92") (unit 1)
        )
      )
    )
  )

  (symbol (lib_id "antmicroCapacitors0402:C_100n_0402") (at 274.32 54.61 270) (mirror x) (unit 1)
    (in_bom yes) (on_board yes) (dnp no)
    (property "Reference" "C88" (at 274.955 50.165 90)
      (effects (font (size 1.524 1.524)) (justify left))
    )
    (property "Value" "C_100n_0402" (at 270.51 54.61 0)
      (effects (font (size 1.524 1.524)) hide)
    )
    (property "Footprint" "antmicro-footprints:C_0402_1005Metric" (at 279.4 49.53 0)
      (effects (font (size 1.524 1.524)) (justify left) hide)
    )
    (property "Datasheet" "https://www.murata.com/products/productdetail?partno=GRM155R61H104KE14%23" (at 274.32 54.61 0)
      (effects (font (size 1.27 1.27)) hide)
    )
    (property "Manufacturer" "Murata" (at 284.48 49.53 0)
      (effects (font (size 1.524 1.524)) (justify left) hide)
    )
    (property "MPN" "GRM155R61H104KE14D" (at 281.94 49.53 0)
      (effects (font (size 1.524 1.524)) (justify left) hide)
    )
    (property "Val" "100n" (at 274.955 53.975 90)
      (effects (font (size 1.27 1.27)) (justify left))
    )
    (property "License" "Apache-2.0" (at 251.46 34.29 0)
      (effects (font (size 1.27 1.27) (thickness 0.15)) (justify left bottom) hide)
    )
    (property "Author" "Antmicro" (at 248.92 34.29 0)
      (effects (font (size 1.27 1.27) (thickness 0.15)) (justify left bottom) hide)
    )
    (property "Voltage" "50V" (at 246.38 34.29 0)
      (effects (font (size 1.27 1.27)) (justify left bottom) hide)
    )
    (property "Dielectric" "X5R" (at 243.84 34.29 0)
      (effects (font (size 1.27 1.27)) (justify left bottom) hide)
    )
    (property "Public" "False" (at 241.3 34.29 0)
      (effects (font (size 1.27 1.27)) (justify left bottom) hide)
    )
    (pin "1")
    (pin "2")
    (instances
      (project "ecp5-dc-scm"
        (path ""
          (reference "C88") (unit 1)
        )
      )
    )
  )

  (symbol (lib_id "antmicroCapacitors0402:C_100n_0402") (at 265.43 54.61 270) (mirror x) (unit 1)
    (in_bom yes) (on_board yes) (dnp no)
    (property "Reference" "C93" (at 265.43 50.165 90)
      (effects (font (size 1.524 1.524)) (justify left))
    )
    (property "Value" "C_100n_0402" (at 261.62 54.61 0)
      (effects (font (size 1.524 1.524)) hide)
    )
    (property "Footprint" "antmicro-footprints:C_0402_1005Metric" (at 270.51 49.53 0)
      (effects (font (size 1.524 1.524)) (justify left) hide)
    )
    (property "Datasheet" "https://www.murata.com/products/productdetail?partno=GRM155R61H104KE14%23" (at 265.43 54.61 0)
      (effects (font (size 1.27 1.27)) hide)
    )
    (property "Manufacturer" "Murata" (at 275.59 49.53 0)
      (effects (font (size 1.524 1.524)) (justify left) hide)
    )
    (property "MPN" "GRM155R61H104KE14D" (at 273.05 49.53 0)
      (effects (font (size 1.524 1.524)) (justify left) hide)
    )
    (property "Val" "100n" (at 266.065 53.975 90)
      (effects (font (size 1.27 1.27)) (justify left))
    )
    (property "License" "Apache-2.0" (at 242.57 34.29 0)
      (effects (font (size 1.27 1.27) (thickness 0.15)) (justify left bottom) hide)
    )
    (property "Author" "Antmicro" (at 240.03 34.29 0)
      (effects (font (size 1.27 1.27) (thickness 0.15)) (justify left bottom) hide)
    )
    (property "Voltage" "50V" (at 237.49 34.29 0)
      (effects (font (size 1.27 1.27)) (justify left bottom) hide)
    )
    (property "Dielectric" "X5R" (at 234.95 34.29 0)
      (effects (font (size 1.27 1.27)) (justify left bottom) hide)
    )
    (property "Public" "False" (at 232.41 34.29 0)
      (effects (font (size 1.27 1.27)) (justify left bottom) hide)
    )
    (pin "1")
    (pin "2")
    (instances
      (project "ecp5-dc-scm"
        (path ""
          (reference "C93") (unit 1)
        )
      )
    )
  )

  (symbol (lib_id "antmicroResistors0402:R_240R_0402") (at 243.84 127 270) (unit 1)
    (in_bom yes) (on_board yes) (dnp no)
    (property "Reference" "R81" (at 245.11 128.27 90)
      (effects (font (size 1.524 1.524)) (justify left))
    )
    (property "Value" "R_240R_0402" (at 240.03 127 0)
      (effects (font (size 1.524 1.524)) hide)
    )
    (property "Footprint" "antmicro-footprints:R_0402_1005Metric" (at 248.92 132.08 0)
      (effects (font (size 1.524 1.524)) (justify left) hide)
    )
    (property "Datasheet" "https://www.bourns.com/docs/product-datasheets/cr.pdf" (at 243.84 127 0)
      (effects (font (size 1.27 1.27)) hide)
    )
    (property "Manufacturer" "Bourns" (at 254 132.08 0)
      (effects (font (size 1.524 1.524)) (justify left) hide)
    )
    (property "MPN" "CR0402-FX-2400GLF" (at 251.46 132.08 0)
      (effects (font (size 1.524 1.524)) (justify left) hide)
    )
    (property "Val" "240R" (at 245.11 130.7592 90)
      (effects (font (size 1.27 1.27)) (justify left))
    )
    (property "License" "Apache-2.0" (at 218.44 147.32 0)
      (effects (font (size 1.27 1.27) (thickness 0.15)) (justify left bottom) hide)
    )
    (property "Author" "Antmicro" (at 215.9 147.32 0)
      (effects (font (size 1.27 1.27) (thickness 0.15)) (justify left bottom) hide)
    )
    (property "Tolerance" "1%" (at 233.68 147.32 0)
      (effects (font (size 1.27 1.27)) (justify left bottom) hide)
    )
    (property "Public" "False" (at 213.36 147.32 0)
      (effects (font (size 1.27 1.27)) (justify left bottom) hide)
    )
    (pin "1")
    (pin "2")
    (instances
      (project "ecp5-dc-scm"
        (path ""
          (reference "R81") (unit 1)
        )
      )
    )
  )

  (symbol (lib_id "antmicroResistorNetworksArrays:8x51R_0602_array") (at 128.27 175.26 0) (unit 1)
    (in_bom yes) (on_board yes) (dnp no) (fields_autoplaced)
    (property "Reference" "R124" (at 133.4135 166.37 0)
      (effects (font (size 1.524 1.524)))
    )
    (property "Value" "8x51R_0602_array" (at 133.4135 168.91 0)
      (effects (font (size 1.524 1.524)))
    )
    (property "Footprint" "antmicro-footprints:R_Array_8x0602_Panasonic_EXB2HV" (at 123.19 158.75 0)
      (effects (font (size 1.524 1.524)) (justify left) hide)
    )
    (property "Datasheet" "http://industrial.panasonic.com/cdbs/www-data/pdf/AOC0000/AOC0000C14.pdf" (at 123.19 156.21 0)
      (effects (font (size 1.524 1.524)) (justify left) hide)
    )
    (property "MPN" "EXB2HV510JV" (at 123.19 151.13 0)
      (effects (font (size 1.524 1.524)) (justify left) hide)
    )
    (property "Manufacturer" "Panasonic" (at 123.19 153.67 0)
      (effects (font (size 1.524 1.524)) (justify left) hide)
    )
    (property "Author" "Antmicro" (at 154.94 198.12 0)
      (effects (font (size 1.27 1.27) (thickness 0.15)) (justify left bottom) hide)
    )
    (property "License" "Apache-2.0" (at 154.94 200.66 0)
      (effects (font (size 1.27 1.27) (thickness 0.15)) (justify left bottom) hide)
    )
    (property "Val" "8x51R_0602" (at 133.4135 171.45 0)
      (effects (font (size 1.27 1.27)))
    )
    (pin "1")
    (pin "10")
    (pin "11")
    (pin "12")
    (pin "13")
    (pin "14")
    (pin "15")
    (pin "16")
    (pin "2")
    (pin "3")
    (pin "4")
    (pin "5")
    (pin "6")
    (pin "7")
    (pin "8")
    (pin "9")
    (instances
      (project "ecp5-dc-scm"
        (path ""
          (reference "R124") (unit 1)
        )
      )
    )
  )

  (symbol (lib_id "antmicroResistorNetworksArrays:8x51R_0602_array") (at 128.27 210.82 0) (unit 1)
    (in_bom yes) (on_board yes) (dnp no) (fields_autoplaced)
    (property "Reference" "R125" (at 133.4135 202.565 0)
      (effects (font (size 1.524 1.524)))
    )
    (property "Value" "8x51R_0602_array" (at 133.4135 205.105 0)
      (effects (font (size 1.524 1.524)))
    )
    (property "Footprint" "antmicro-footprints:R_Array_8x0602_Panasonic_EXB2HV" (at 123.19 194.31 0)
      (effects (font (size 1.524 1.524)) (justify left) hide)
    )
    (property "Datasheet" "http://industrial.panasonic.com/cdbs/www-data/pdf/AOC0000/AOC0000C14.pdf" (at 123.19 191.77 0)
      (effects (font (size 1.524 1.524)) (justify left) hide)
    )
    (property "MPN" "EXB2HV510JV" (at 123.19 186.69 0)
      (effects (font (size 1.524 1.524)) (justify left) hide)
    )
    (property "Manufacturer" "Panasonic" (at 123.19 189.23 0)
      (effects (font (size 1.524 1.524)) (justify left) hide)
    )
    (property "Author" "Antmicro" (at 154.94 233.68 0)
      (effects (font (size 1.27 1.27) (thickness 0.15)) (justify left bottom) hide)
    )
    (property "License" "Apache-2.0" (at 154.94 236.22 0)
      (effects (font (size 1.27 1.27) (thickness 0.15)) (justify left bottom) hide)
    )
    (property "Val" "8x51R_0602" (at 133.4135 207.645 0)
      (effects (font (size 1.27 1.27)))
    )
    (pin "1")
    (pin "10")
    (pin "11")
    (pin "12")
    (pin "13")
    (pin "14")
    (pin "15")
    (pin "16")
    (pin "2")
    (pin "3")
    (pin "4")
    (pin "5")
    (pin "6")
    (pin "7")
    (pin "8")
    (pin "9")
    (instances
      (project "ecp5-dc-scm"
        (path ""
          (reference "R125") (unit 1)
        )
      )
    )
  )

  (symbol (lib_id "antmicroResistorNetworksArrays:8x51R_0602_array") (at 128.27 246.38 0) (unit 1)
    (in_bom yes) (on_board yes) (dnp no) (fields_autoplaced)
    (property "Reference" "R136" (at 133.4135 238.125 0)
      (effects (font (size 1.524 1.524)))
    )
    (property "Value" "8x51R_0602_array" (at 133.4135 240.665 0)
      (effects (font (size 1.524 1.524)))
    )
    (property "Footprint" "antmicro-footprints:R_Array_8x0602_Panasonic_EXB2HV" (at 123.19 229.87 0)
      (effects (font (size 1.524 1.524)) (justify left) hide)
    )
    (property "Datasheet" "http://industrial.panasonic.com/cdbs/www-data/pdf/AOC0000/AOC0000C14.pdf" (at 123.19 227.33 0)
      (effects (font (size 1.524 1.524)) (justify left) hide)
    )
    (property "MPN" "EXB2HV510JV" (at 123.19 222.25 0)
      (effects (font (size 1.524 1.524)) (justify left) hide)
    )
    (property "Manufacturer" "Panasonic" (at 123.19 224.79 0)
      (effects (font (size 1.524 1.524)) (justify left) hide)
    )
    (property "Author" "Antmicro" (at 154.94 269.24 0)
      (effects (font (size 1.27 1.27) (thickness 0.15)) (justify left bottom) hide)
    )
    (property "License" "Apache-2.0" (at 154.94 271.78 0)
      (effects (font (size 1.27 1.27) (thickness 0.15)) (justify left bottom) hide)
    )
    (property "Val" "8x51R_0602" (at 133.4135 243.205 0)
      (effects (font (size 1.27 1.27)))
    )
    (pin "1")
    (pin "10")
    (pin "11")
    (pin "12")
    (pin "13")
    (pin "14")
    (pin "15")
    (pin "16")
    (pin "2")
    (pin "3")
    (pin "4")
    (pin "5")
    (pin "6")
    (pin "7")
    (pin "8")
    (pin "9")
    (instances
      (project "ecp5-dc-scm"
        (path ""
          (reference "R136") (unit 1)
        )
      )
    )
  )

  (symbol (lib_id "antmicroCapacitors0402:C_10u_0402") (at 180.34 175.26 90) (unit 1)
    (in_bom yes) (on_board yes) (dnp no)
    (property "Reference" "C197" (at 177.8 174.625 0)
      (effects (font (size 1.524 1.524)) (justify left))
    )
    (property "Value" "C_10u_0402" (at 184.15 175.26 0)
      (effects (font (size 1.524 1.524)) hide)
    )
    (property "Footprint" "antmicro-footprints:C_0402_1005Metric" (at 175.26 170.18 0)
      (effects (font (size 1.524 1.524)) (justify left) hide)
    )
    (property "Datasheet" "https://www.yageo.com/en/Chart/Download/pdf/CC0402MRX5R5BB106" (at 180.34 175.26 0)
      (effects (font (size 1.27 1.27)) hide)
    )
    (property "Manufacturer" "YAGEO" (at 170.18 170.18 0)
      (effects (font (size 1.524 1.524)) (justify left) hide)
    )
    (property "MPN" "CC0402MRX5R5BB106" (at 172.72 170.18 0)
      (effects (font (size 1.524 1.524)) (justify left) hide)
    )
    (property "Val" "10u" (at 182.88 174.625 0)
      (effects (font (size 1.27 1.27)) (justify left))
    )
    (property "License" "Apache-2.0" (at 203.2 154.94 0)
      (effects (font (size 1.27 1.27) (thickness 0.15)) (justify left bottom) hide)
    )
    (property "Author" "Antmicro" (at 205.74 154.94 0)
      (effects (font (size 1.27 1.27) (thickness 0.15)) (justify left bottom) hide)
    )
    (property "Voltage" "" (at 208.28 154.94 0)
      (effects (font (size 1.27 1.27)) (justify left bottom) hide)
    )
    (property "Dielectric" "" (at 210.82 154.94 0)
      (effects (font (size 1.27 1.27)) (justify left bottom) hide)
    )
    (property "Public" "False" (at 213.36 154.94 0)
      (effects (font (size 1.27 1.27)) (justify left bottom) hide)
    )
    (pin "1")
    (pin "2")
    (instances
      (project "ecp5-dc-scm"
        (path ""
          (reference "C197") (unit 1)
        )
      )
    )
  )

  (symbol (lib_id "antmicroResistors0402:R_10k_0402") (at 171.45 222.25 90) (mirror x) (unit 1)
    (in_bom yes) (on_board yes) (dnp no)
    (property "Reference" "R78" (at 168.91 223.52 90)
      (effects (font (size 1.524 1.524)) (justify left))
    )
    (property "Value" "R_10k_0402" (at 175.26 222.25 0)
      (effects (font (size 1.524 1.524)) hide)
    )
    (property "Footprint" "antmicro-footprints:R_0402_1005Metric" (at 166.37 227.33 0)
      (effects (font (size 1.524 1.524)) (justify left) hide)
    )
    (property "Datasheet" "https://www.bourns.com/docs/product-datasheets/cr.pdf" (at 171.45 222.25 0)
      (effects (font (size 1.27 1.27)) hide)
    )
    (property "Manufacturer" "Bourns" (at 161.29 227.33 0)
      (effects (font (size 1.524 1.524)) (justify left) hide)
    )
    (property "MPN" "CR0402-FX-1002GLF" (at 163.83 227.33 0)
      (effects (font (size 1.524 1.524)) (justify left) hide)
    )
    (property "Val" "10k" (at 168.91 226.06 90)
      (effects (font (size 1.27 1.27)) (justify left))
    )
    (property "License" "Apache-2.0" (at 196.85 242.57 0)
      (effects (font (size 1.27 1.27) (thickness 0.15)) (justify left bottom) hide)
    )
    (property "Author" "Antmicro" (at 199.39 242.57 0)
      (effects (font (size 1.27 1.27) (thickness 0.15)) (justify left bottom) hide)
    )
    (property "Tolerance" "1%" (at 181.61 242.57 0)
      (effects (font (size 1.27 1.27)) (justify left bottom) hide)
    )
    (property "Public" "False" (at 201.93 242.57 0)
      (effects (font (size 1.27 1.27)) (justify left bottom) hide)
    )
    (pin "1")
    (pin "2")
    (instances
      (project "ecp5-dc-scm"
        (path ""
          (reference "R78") (unit 1)
        )
      )
    )
  )

  (symbol (lib_id "antmicroCapacitors0402:C_10u_0402") (at 187.96 175.26 90) (unit 1)
    (in_bom yes) (on_board yes) (dnp no)
    (property "Reference" "C198" (at 185.42 174.625 0)
      (effects (font (size 1.524 1.524)) (justify left))
    )
    (property "Value" "C_10u_0402" (at 191.77 175.26 0)
      (effects (font (size 1.524 1.524)) hide)
    )
    (property "Footprint" "antmicro-footprints:C_0402_1005Metric" (at 182.88 170.18 0)
      (effects (font (size 1.524 1.524)) (justify left) hide)
    )
    (property "Datasheet" "https://www.yageo.com/en/Chart/Download/pdf/CC0402MRX5R5BB106" (at 187.96 175.26 0)
      (effects (font (size 1.27 1.27)) hide)
    )
    (property "Manufacturer" "YAGEO" (at 177.8 170.18 0)
      (effects (font (size 1.524 1.524)) (justify left) hide)
    )
    (property "MPN" "CC0402MRX5R5BB106" (at 180.34 170.18 0)
      (effects (font (size 1.524 1.524)) (justify left) hide)
    )
    (property "Val" "10u" (at 190.5 174.625 0)
      (effects (font (size 1.27 1.27)) (justify left))
    )
    (property "License" "Apache-2.0" (at 210.82 154.94 0)
      (effects (font (size 1.27 1.27) (thickness 0.15)) (justify left bottom) hide)
    )
    (property "Author" "Antmicro" (at 213.36 154.94 0)
      (effects (font (size 1.27 1.27) (thickness 0.15)) (justify left bottom) hide)
    )
    (property "Voltage" "" (at 215.9 154.94 0)
      (effects (font (size 1.27 1.27)) (justify left bottom) hide)
    )
    (property "Dielectric" "" (at 218.44 154.94 0)
      (effects (font (size 1.27 1.27)) (justify left bottom) hide)
    )
    (property "Public" "False" (at 220.98 154.94 0)
      (effects (font (size 1.27 1.27)) (justify left bottom) hide)
    )
    (pin "1")
    (pin "2")
    (instances
      (project "ecp5-dc-scm"
        (path ""
          (reference "C198") (unit 1)
        )
      )
    )
  )

  (symbol (lib_id "antmicroCapacitors0402:C_10u_0402") (at 195.58 175.26 90) (unit 1)
    (in_bom yes) (on_board yes) (dnp no)
    (property "Reference" "C199" (at 193.04 174.625 0)
      (effects (font (size 1.524 1.524)) (justify left))
    )
    (property "Value" "C_10u_0402" (at 199.39 175.26 0)
      (effects (font (size 1.524 1.524)) hide)
    )
    (property "Footprint" "antmicro-footprints:C_0402_1005Metric" (at 190.5 170.18 0)
      (effects (font (size 1.524 1.524)) (justify left) hide)
    )
    (property "Datasheet" "https://www.yageo.com/en/Chart/Download/pdf/CC0402MRX5R5BB106" (at 195.58 175.26 0)
      (effects (font (size 1.27 1.27)) hide)
    )
    (property "Manufacturer" "YAGEO" (at 185.42 170.18 0)
      (effects (font (size 1.524 1.524)) (justify left) hide)
    )
    (property "MPN" "CC0402MRX5R5BB106" (at 187.96 170.18 0)
      (effects (font (size 1.524 1.524)) (justify left) hide)
    )
    (property "Val" "10u" (at 198.12 174.625 0)
      (effects (font (size 1.27 1.27)) (justify left))
    )
    (property "License" "Apache-2.0" (at 218.44 154.94 0)
      (effects (font (size 1.27 1.27) (thickness 0.15)) (justify left bottom) hide)
    )
    (property "Author" "Antmicro" (at 220.98 154.94 0)
      (effects (font (size 1.27 1.27) (thickness 0.15)) (justify left bottom) hide)
    )
    (property "Voltage" "" (at 223.52 154.94 0)
      (effects (font (size 1.27 1.27)) (justify left bottom) hide)
    )
    (property "Dielectric" "" (at 226.06 154.94 0)
      (effects (font (size 1.27 1.27)) (justify left bottom) hide)
    )
    (property "Public" "False" (at 228.6 154.94 0)
      (effects (font (size 1.27 1.27)) (justify left bottom) hide)
    )
    (pin "1")
    (pin "2")
    (instances
      (project "ecp5-dc-scm"
        (path ""
          (reference "C199") (unit 1)
        )
      )
    )
  )

  (symbol (lib_id "antmicroCapacitors0402:C_100n_0402") (at 203.2 243.84 270) (mirror x) (unit 1)
    (in_bom yes) (on_board yes) (dnp no)
    (property "Reference" "C202" (at 205.74 243.205 0)
      (effects (font (size 1.524 1.524)) (justify left))
    )
    (property "Value" "C_100n_0402" (at 199.39 243.84 0)
      (effects (font (size 1.524 1.524)) hide)
    )
    (property "Footprint" "antmicro-footprints:C_0402_1005Metric" (at 208.28 238.76 0)
      (effects (font (size 1.524 1.524)) (justify left) hide)
    )
    (property "Datasheet" "https://www.murata.com/products/productdetail?partno=GRM155R61H104KE14%23" (at 203.2 243.84 0)
      (effects (font (size 1.27 1.27)) hide)
    )
    (property "Manufacturer" "Murata" (at 213.36 238.76 0)
      (effects (font (size 1.524 1.524)) (justify left) hide)
    )
    (property "MPN" "GRM155R61H104KE14D" (at 210.82 238.76 0)
      (effects (font (size 1.524 1.524)) (justify left) hide)
    )
    (property "Val" "100n" (at 200.66 243.205 0)
      (effects (font (size 1.27 1.27)) (justify left))
    )
    (property "License" "Apache-2.0" (at 180.34 223.52 0)
      (effects (font (size 1.27 1.27) (thickness 0.15)) (justify left bottom) hide)
    )
    (property "Author" "Antmicro" (at 177.8 223.52 0)
      (effects (font (size 1.27 1.27) (thickness 0.15)) (justify left bottom) hide)
    )
    (property "Voltage" "50V" (at 175.26 223.52 0)
      (effects (font (size 1.27 1.27)) (justify left bottom) hide)
    )
    (property "Dielectric" "X5R" (at 172.72 223.52 0)
      (effects (font (size 1.27 1.27)) (justify left bottom) hide)
    )
    (property "Public" "False" (at 170.18 223.52 0)
      (effects (font (size 1.27 1.27)) (justify left bottom) hide)
    )
    (pin "1")
    (pin "2")
    (instances
      (project "ecp5-dc-scm"
        (path ""
          (reference "C202") (unit 1)
        )
      )
    )
  )

  (symbol (lib_id "antmicropower:GND") (at 242.57 232.41 0) (mirror y) (unit 1)
    (in_bom yes) (on_board yes) (dnp no)
    (property "Reference" "#PWR0120" (at 242.57 238.76 0)
      (effects (font (size 1.27 1.27)) hide)
    )
    (property "Value" "GND" (at 242.443 236.8042 0)
      (effects (font (size 1.27 1.27)))
    )
    (property "Footprint" "" (at 242.57 232.41 0)
      (effects (font (size 1.27 1.27)) hide)
    )
    (property "Datasheet" "" (at 242.57 232.41 0)
      (effects (font (size 1.27 1.27)) hide)
    )
    (property "Author" "Antmicro" (at 233.68 240.03 0)
      (effects (font (size 1.27 1.27) (thickness 0.15)) (justify left bottom) hide)
    )
    (property "License" "Apache-2.0" (at 233.68 242.57 0)
      (effects (font (size 1.27 1.27) (thickness 0.15)) (justify left bottom) hide)
    )
    (pin "1")
    (instances
      (project "ecp5-dc-scm"
        (path ""
          (reference "#PWR0120") (unit 1)
        )
      )
    )
  )

  (symbol (lib_id "antmicroResistors0402:R_10k_0402") (at 171.45 212.09 270) (unit 1)
    (in_bom yes) (on_board yes) (dnp no)
    (property "Reference" "R79" (at 173.228 210.947 90)
      (effects (font (size 1.524 1.524)) (justify left))
    )
    (property "Value" "R_10k_0402" (at 167.64 212.09 0)
      (effects (font (size 1.524 1.524)) hide)
    )
    (property "Footprint" "antmicro-footprints:R_0402_1005Metric" (at 176.53 217.17 0)
      (effects (font (size 1.524 1.524)) (justify left) hide)
    )
    (property "Datasheet" "https://www.bourns.com/docs/product-datasheets/cr.pdf" (at 171.45 212.09 0)
      (effects (font (size 1.27 1.27)) hide)
    )
    (property "Manufacturer" "Bourns" (at 181.61 217.17 0)
      (effects (font (size 1.524 1.524)) (justify left) hide)
    )
    (property "MPN" "CR0402-FX-1002GLF" (at 179.07 217.17 0)
      (effects (font (size 1.524 1.524)) (justify left) hide)
    )
    (property "Val" "10k" (at 173.228 213.4362 90)
      (effects (font (size 1.27 1.27)) (justify left))
    )
    (property "License" "Apache-2.0" (at 146.05 232.41 0)
      (effects (font (size 1.27 1.27) (thickness 0.15)) (justify left bottom) hide)
    )
    (property "Author" "Antmicro" (at 143.51 232.41 0)
      (effects (font (size 1.27 1.27) (thickness 0.15)) (justify left bottom) hide)
    )
    (property "Tolerance" "1%" (at 161.29 232.41 0)
      (effects (font (size 1.27 1.27)) (justify left bottom) hide)
    )
    (property "Public" "False" (at 140.97 232.41 0)
      (effects (font (size 1.27 1.27)) (justify left bottom) hide)
    )
    (pin "1")
    (pin "2")
    (instances
      (project "ecp5-dc-scm"
        (path ""
          (reference "R79") (unit 1)
        )
      )
    )
  )

  (symbol (lib_id "antmicroResistors0402:R_10k_0402") (at 200.66 213.36 0) (unit 1)
    (in_bom yes) (on_board yes) (dnp no) (fields_autoplaced)
    (property "Reference" "R80" (at 203.2 207.01 0)
      (effects (font (size 1.524 1.524)))
    )
    (property "Value" "R_10k_0402" (at 200.66 217.17 0)
      (effects (font (size 1.524 1.524)) hide)
    )
    (property "Footprint" "antmicro-footprints:R_0402_1005Metric" (at 205.74 208.28 0)
      (effects (font (size 1.524 1.524)) (justify left) hide)
    )
    (property "Datasheet" "https://www.bourns.com/docs/product-datasheets/cr.pdf" (at 200.66 213.36 0)
      (effects (font (size 1.27 1.27)) hide)
    )
    (property "Manufacturer" "Bourns" (at 205.74 203.2 0)
      (effects (font (size 1.524 1.524)) (justify left) hide)
    )
    (property "MPN" "CR0402-FX-1002GLF" (at 205.74 205.74 0)
      (effects (font (size 1.524 1.524)) (justify left) hide)
    )
    (property "Val" "10k" (at 203.2 209.55 0)
      (effects (font (size 1.27 1.27)))
    )
    (property "License" "Apache-2.0" (at 220.98 238.76 0)
      (effects (font (size 1.27 1.27) (thickness 0.15)) (justify left bottom) hide)
    )
    (property "Author" "Antmicro" (at 220.98 241.3 0)
      (effects (font (size 1.27 1.27) (thickness 0.15)) (justify left bottom) hide)
    )
    (property "Tolerance" "1%" (at 220.98 223.52 0)
      (effects (font (size 1.27 1.27)) (justify left bottom) hide)
    )
    (property "Public" "False" (at 220.98 243.84 0)
      (effects (font (size 1.27 1.27)) (justify left bottom) hide)
    )
    (pin "1")
    (pin "2")
    (instances
      (project "ecp5-dc-scm"
        (path ""
          (reference "R80") (unit 1)
        )
      )
    )
  )

  (symbol (lib_id "antmicropower:GND") (at 195.58 180.34 0) (unit 1)
    (in_bom yes) (on_board yes) (dnp no)
    (property "Reference" "#PWR0116" (at 195.58 186.69 0)
      (effects (font (size 1.27 1.27)) hide)
    )
    (property "Value" "GND" (at 195.707 184.7342 0)
      (effects (font (size 1.27 1.27)))
    )
    (property "Footprint" "" (at 195.58 180.34 0)
      (effects (font (size 1.27 1.27)) hide)
    )
    (property "Datasheet" "" (at 195.58 180.34 0)
      (effects (font (size 1.27 1.27)) hide)
    )
    (property "Author" "Antmicro" (at 204.47 187.96 0)
      (effects (font (size 1.27 1.27) (thickness 0.15)) (justify left bottom) hide)
    )
    (property "License" "Apache-2.0" (at 204.47 190.5 0)
      (effects (font (size 1.27 1.27) (thickness 0.15)) (justify left bottom) hide)
    )
    (pin "1")
    (instances
      (project "ecp5-dc-scm"
        (path ""
          (reference "#PWR0116") (unit 1)
        )
      )
    )
  )

  (symbol (lib_id "antmicropower:GND") (at 194.31 250.19 0) (mirror y) (unit 1)
    (in_bom yes) (on_board yes) (dnp no)
    (property "Reference" "#PWR052" (at 194.31 256.54 0)
      (effects (font (size 1.27 1.27)) hide)
    )
    (property "Value" "GND" (at 194.183 254.5842 0)
      (effects (font (size 1.27 1.27)))
    )
    (property "Footprint" "" (at 194.31 250.19 0)
      (effects (font (size 1.27 1.27)) hide)
    )
    (property "Datasheet" "" (at 194.31 250.19 0)
      (effects (font (size 1.27 1.27)) hide)
    )
    (property "Author" "Antmicro" (at 185.42 257.81 0)
      (effects (font (size 1.27 1.27) (thickness 0.15)) (justify left bottom) hide)
    )
    (property "License" "Apache-2.0" (at 185.42 260.35 0)
      (effects (font (size 1.27 1.27) (thickness 0.15)) (justify left bottom) hide)
    )
    (pin "1")
    (instances
      (project "ecp5-dc-scm"
        (path ""
          (reference "#PWR052") (unit 1)
        )
      )
    )
  )

  (symbol (lib_id "antmicropower:GND") (at 229.87 232.41 0) (unit 1)
    (in_bom yes) (on_board yes) (dnp no)
    (property "Reference" "#PWR051" (at 229.87 238.76 0)
      (effects (font (size 1.27 1.27)) hide)
    )
    (property "Value" "GND" (at 229.997 236.8042 0)
      (effects (font (size 1.27 1.27)))
    )
    (property "Footprint" "" (at 229.87 232.41 0)
      (effects (font (size 1.27 1.27)) hide)
    )
    (property "Datasheet" "" (at 229.87 232.41 0)
      (effects (font (size 1.27 1.27)) hide)
    )
    (property "Author" "Antmicro" (at 238.76 240.03 0)
      (effects (font (size 1.27 1.27) (thickness 0.15)) (justify left bottom) hide)
    )
    (property "License" "Apache-2.0" (at 238.76 242.57 0)
      (effects (font (size 1.27 1.27) (thickness 0.15)) (justify left bottom) hide)
    )
    (pin "1")
    (instances
      (project "ecp5-dc-scm"
        (path ""
          (reference "#PWR051") (unit 1)
        )
      )
    )
  )

  (symbol (lib_id "antmicroCapacitors0402:C_10u_0402") (at 184.15 199.39 90) (unit 1)
    (in_bom yes) (on_board yes) (dnp no)
    (property "Reference" "C78" (at 186.69 195.5736 90)
      (effects (font (size 1.524 1.524)) (justify right))
    )
    (property "Value" "C_10u_0402" (at 187.96 199.39 0)
      (effects (font (size 1.524 1.524)) hide)
    )
    (property "Footprint" "antmicro-footprints:C_0402_1005Metric" (at 179.07 194.31 0)
      (effects (font (size 1.524 1.524)) (justify left) hide)
    )
    (property "Datasheet" "https://www.yageo.com/en/Chart/Download/pdf/CC0402MRX5R5BB106" (at 184.15 199.39 0)
      (effects (font (size 1.27 1.27)) hide)
    )
    (property "Manufacturer" "YAGEO" (at 173.99 194.31 0)
      (effects (font (size 1.524 1.524)) (justify left) hide)
    )
    (property "MPN" "CC0402MRX5R5BB106" (at 176.53 194.31 0)
      (effects (font (size 1.524 1.524)) (justify left) hide)
    )
    (property "Val" "10u" (at 186.69 198.1136 90)
      (effects (font (size 1.27 1.27)) (justify right))
    )
    (property "License" "Apache-2.0" (at 207.01 179.07 0)
      (effects (font (size 1.27 1.27) (thickness 0.15)) (justify left bottom) hide)
    )
    (property "Author" "Antmicro" (at 209.55 179.07 0)
      (effects (font (size 1.27 1.27) (thickness 0.15)) (justify left bottom) hide)
    )
    (property "Voltage" "" (at 212.09 179.07 0)
      (effects (font (size 1.27 1.27)) (justify left bottom) hide)
    )
    (property "Dielectric" "" (at 214.63 179.07 0)
      (effects (font (size 1.27 1.27)) (justify left bottom) hide)
    )
    (property "Public" "False" (at 217.17 179.07 0)
      (effects (font (size 1.27 1.27)) (justify left bottom) hide)
    )
    (pin "1")
    (pin "2")
    (instances
      (project "ecp5-dc-scm"
        (path ""
          (reference "C78") (unit 1)
        )
      )
    )
  )

  (symbol (lib_id "antmicropower:GND") (at 184.15 200.66 0) (mirror y) (unit 1)
    (in_bom yes) (on_board yes) (dnp no)
    (property "Reference" "#PWR053" (at 184.15 207.01 0)
      (effects (font (size 1.27 1.27)) hide)
    )
    (property "Value" "GND" (at 184.023 205.0542 0)
      (effects (font (size 1.27 1.27)))
    )
    (property "Footprint" "" (at 184.15 200.66 0)
      (effects (font (size 1.27 1.27)) hide)
    )
    (property "Datasheet" "" (at 184.15 200.66 0)
      (effects (font (size 1.27 1.27)) hide)
    )
    (property "Author" "Antmicro" (at 175.26 208.28 0)
      (effects (font (size 1.27 1.27) (thickness 0.15)) (justify left bottom) hide)
    )
    (property "License" "Apache-2.0" (at 175.26 210.82 0)
      (effects (font (size 1.27 1.27) (thickness 0.15)) (justify left bottom) hide)
    )
    (pin "1")
    (instances
      (project "ecp5-dc-scm"
        (path ""
          (reference "#PWR053") (unit 1)
        )
      )
    )
  )

  (symbol (lib_id "antmicropower:GND") (at 116.84 54.61 0) (unit 1)
    (in_bom yes) (on_board yes) (dnp no)
    (property "Reference" "#PWR054" (at 116.84 60.96 0)
      (effects (font (size 1.27 1.27)) hide)
    )
    (property "Value" "GND" (at 116.967 59.0042 0)
      (effects (font (size 1.27 1.27)))
    )
    (property "Footprint" "" (at 116.84 54.61 0)
      (effects (font (size 1.27 1.27)) hide)
    )
    (property "Datasheet" "" (at 116.84 54.61 0)
      (effects (font (size 1.27 1.27)) hide)
    )
    (property "Author" "Antmicro" (at 125.73 62.23 0)
      (effects (font (size 1.27 1.27) (thickness 0.15)) (justify left bottom) hide)
    )
    (property "License" "Apache-2.0" (at 125.73 64.77 0)
      (effects (font (size 1.27 1.27) (thickness 0.15)) (justify left bottom) hide)
    )
    (pin "1")
    (instances
      (project "ecp5-dc-scm"
        (path ""
          (reference "#PWR054") (unit 1)
        )
      )
    )
  )

  (symbol (lib_id "antmicropower:GND") (at 116.84 76.2 0) (unit 1)
    (in_bom yes) (on_board yes) (dnp no)
    (property "Reference" "#PWR055" (at 116.84 82.55 0)
      (effects (font (size 1.27 1.27)) hide)
    )
    (property "Value" "GND" (at 116.967 80.5942 0)
      (effects (font (size 1.27 1.27)))
    )
    (property "Footprint" "" (at 116.84 76.2 0)
      (effects (font (size 1.27 1.27)) hide)
    )
    (property "Datasheet" "" (at 116.84 76.2 0)
      (effects (font (size 1.27 1.27)) hide)
    )
    (property "Author" "Antmicro" (at 125.73 83.82 0)
      (effects (font (size 1.27 1.27) (thickness 0.15)) (justify left bottom) hide)
    )
    (property "License" "Apache-2.0" (at 125.73 86.36 0)
      (effects (font (size 1.27 1.27) (thickness 0.15)) (justify left bottom) hide)
    )
    (pin "1")
    (instances
      (project "ecp5-dc-scm"
        (path ""
          (reference "#PWR055") (unit 1)
        )
      )
    )
  )

  (symbol (lib_id "antmicropower:GND") (at 274.32 58.42 0) (unit 1)
    (in_bom yes) (on_board yes) (dnp no)
    (property "Reference" "#PWR056" (at 274.32 64.77 0)
      (effects (font (size 1.27 1.27)) hide)
    )
    (property "Value" "GND" (at 274.447 62.8142 0)
      (effects (font (size 1.27 1.27)))
    )
    (property "Footprint" "" (at 274.32 58.42 0)
      (effects (font (size 1.27 1.27)) hide)
    )
    (property "Datasheet" "" (at 274.32 58.42 0)
      (effects (font (size 1.27 1.27)) hide)
    )
    (property "Author" "Antmicro" (at 283.21 66.04 0)
      (effects (font (size 1.27 1.27) (thickness 0.15)) (justify left bottom) hide)
    )
    (property "License" "Apache-2.0" (at 283.21 68.58 0)
      (effects (font (size 1.27 1.27) (thickness 0.15)) (justify left bottom) hide)
    )
    (pin "1")
    (instances
      (project "ecp5-dc-scm"
        (path ""
          (reference "#PWR056") (unit 1)
        )
      )
    )
  )

  (symbol (lib_id "antmicropower:GND") (at 151.13 110.49 0) (unit 1)
    (in_bom yes) (on_board yes) (dnp no)
    (property "Reference" "#PWR057" (at 151.13 116.84 0)
      (effects (font (size 1.27 1.27)) hide)
    )
    (property "Value" "GND" (at 151.257 113.7412 90)
      (effects (font (size 1.27 1.27)) (justify right))
    )
    (property "Footprint" "" (at 151.13 110.49 0)
      (effects (font (size 1.27 1.27)) hide)
    )
    (property "Datasheet" "" (at 151.13 110.49 0)
      (effects (font (size 1.27 1.27)) hide)
    )
    (property "Author" "Antmicro" (at 160.02 118.11 0)
      (effects (font (size 1.27 1.27) (thickness 0.15)) (justify left bottom) hide)
    )
    (property "License" "Apache-2.0" (at 160.02 120.65 0)
      (effects (font (size 1.27 1.27) (thickness 0.15)) (justify left bottom) hide)
    )
    (pin "1")
    (instances
      (project "ecp5-dc-scm"
        (path ""
          (reference "#PWR057") (unit 1)
        )
      )
    )
  )

  (symbol (lib_id "antmicroCapacitors0402:C_100n_0402") (at 194.31 243.84 270) (mirror x) (unit 1)
    (in_bom yes) (on_board yes) (dnp no)
    (property "Reference" "C240" (at 196.85 243.205 0)
      (effects (font (size 1.524 1.524)) (justify left))
    )
    (property "Value" "C_100n_0402" (at 190.5 243.84 0)
      (effects (font (size 1.524 1.524)) hide)
    )
    (property "Footprint" "antmicro-footprints:C_0402_1005Metric" (at 199.39 238.76 0)
      (effects (font (size 1.524 1.524)) (justify left) hide)
    )
    (property "Datasheet" "https://www.murata.com/products/productdetail?partno=GRM155R61H104KE14%23" (at 194.31 243.84 0)
      (effects (font (size 1.27 1.27)) hide)
    )
    (property "Manufacturer" "Murata" (at 204.47 238.76 0)
      (effects (font (size 1.524 1.524)) (justify left) hide)
    )
    (property "MPN" "GRM155R61H104KE14D" (at 201.93 238.76 0)
      (effects (font (size 1.524 1.524)) (justify left) hide)
    )
    (property "Val" "100n" (at 191.77 243.205 0)
      (effects (font (size 1.27 1.27)) (justify left))
    )
    (property "License" "Apache-2.0" (at 171.45 223.52 0)
      (effects (font (size 1.27 1.27) (thickness 0.15)) (justify left bottom) hide)
    )
    (property "Author" "Antmicro" (at 168.91 223.52 0)
      (effects (font (size 1.27 1.27) (thickness 0.15)) (justify left bottom) hide)
    )
    (property "Voltage" "50V" (at 166.37 223.52 0)
      (effects (font (size 1.27 1.27)) (justify left bottom) hide)
    )
    (property "Dielectric" "X5R" (at 163.83 223.52 0)
      (effects (font (size 1.27 1.27)) (justify left bottom) hide)
    )
    (property "Public" "False" (at 161.29 223.52 0)
      (effects (font (size 1.27 1.27)) (justify left bottom) hide)
    )
    (pin "1")
    (pin "2")
    (instances
      (project "ecp5-dc-scm"
        (path ""
          (reference "C240") (unit 1)
        )
      )
    )
  )

  (symbol (lib_id "antmicroCapacitors0402:C_100n_0402") (at 250.19 228.6 270) (mirror x) (unit 1)
    (in_bom yes) (on_board yes) (dnp no) (fields_autoplaced)
    (property "Reference" "C200" (at 252.73 224.7836 90)
      (effects (font (size 1.524 1.524)) (justify left))
    )
    (property "Value" "C_100n_0402" (at 246.38 228.6 0)
      (effects (font (size 1.524 1.524)) hide)
    )
    (property "Footprint" "antmicro-footprints:C_0402_1005Metric" (at 255.27 223.52 0)
      (effects (font (size 1.524 1.524)) (justify left) hide)
    )
    (property "Datasheet" "https://www.murata.com/products/productdetail?partno=GRM155R61H104KE14%23" (at 250.19 228.6 0)
      (effects (font (size 1.27 1.27)) hide)
    )
    (property "Manufacturer" "Murata" (at 260.35 223.52 0)
      (effects (font (size 1.524 1.524)) (justify left) hide)
    )
    (property "MPN" "GRM155R61H104KE14D" (at 257.81 223.52 0)
      (effects (font (size 1.524 1.524)) (justify left) hide)
    )
    (property "Val" "100n" (at 252.73 227.3236 90)
      (effects (font (size 1.27 1.27)) (justify left))
    )
    (property "License" "Apache-2.0" (at 227.33 208.28 0)
      (effects (font (size 1.27 1.27) (thickness 0.15)) (justify left bottom) hide)
    )
    (property "Author" "Antmicro" (at 224.79 208.28 0)
      (effects (font (size 1.27 1.27) (thickness 0.15)) (justify left bottom) hide)
    )
    (property "Voltage" "50V" (at 222.25 208.28 0)
      (effects (font (size 1.27 1.27)) (justify left bottom) hide)
    )
    (property "Dielectric" "X5R" (at 219.71 208.28 0)
      (effects (font (size 1.27 1.27)) (justify left bottom) hide)
    )
    (property "Public" "False" (at 217.17 208.28 0)
      (effects (font (size 1.27 1.27)) (justify left bottom) hide)
    )
    (pin "1")
    (pin "2")
    (instances
      (project "ecp5-dc-scm"
        (path ""
          (reference "C200") (unit 1)
        )
      )
    )
  )

  (symbol (lib_id "antmicroCapacitors0402:C_100n_0402") (at 242.57 228.6 270) (mirror x) (unit 1)
    (in_bom yes) (on_board yes) (dnp no) (fields_autoplaced)
    (property "Reference" "C201" (at 240.03 224.7836 90)
      (effects (font (size 1.524 1.524)) (justify right))
    )
    (property "Value" "C_100n_0402" (at 238.76 228.6 0)
      (effects (font (size 1.524 1.524)) hide)
    )
    (property "Footprint" "antmicro-footprints:C_0402_1005Metric" (at 247.65 223.52 0)
      (effects (font (size 1.524 1.524)) (justify left) hide)
    )
    (property "Datasheet" "https://www.murata.com/products/productdetail?partno=GRM155R61H104KE14%23" (at 242.57 228.6 0)
      (effects (font (size 1.27 1.27)) hide)
    )
    (property "Manufacturer" "Murata" (at 252.73 223.52 0)
      (effects (font (size 1.524 1.524)) (justify left) hide)
    )
    (property "MPN" "GRM155R61H104KE14D" (at 250.19 223.52 0)
      (effects (font (size 1.524 1.524)) (justify left) hide)
    )
    (property "Val" "100n" (at 240.03 227.3236 90)
      (effects (font (size 1.27 1.27)) (justify right))
    )
    (property "License" "Apache-2.0" (at 219.71 208.28 0)
      (effects (font (size 1.27 1.27) (thickness 0.15)) (justify left bottom) hide)
    )
    (property "Author" "Antmicro" (at 217.17 208.28 0)
      (effects (font (size 1.27 1.27) (thickness 0.15)) (justify left bottom) hide)
    )
    (property "Voltage" "50V" (at 214.63 208.28 0)
      (effects (font (size 1.27 1.27)) (justify left bottom) hide)
    )
    (property "Dielectric" "X5R" (at 212.09 208.28 0)
      (effects (font (size 1.27 1.27)) (justify left bottom) hide)
    )
    (property "Public" "False" (at 209.55 208.28 0)
      (effects (font (size 1.27 1.27)) (justify left bottom) hide)
    )
    (pin "1")
    (pin "2")
    (instances
      (project "ecp5-dc-scm"
        (path ""
          (reference "C201") (unit 1)
        )
      )
    )
  )

  (symbol (lib_id "antmicroCapacitors0402:C_100n_0402") (at 142.24 107.95 0) (unit 1)
    (in_bom yes) (on_board yes) (dnp no)
    (property "Reference" "C94" (at 144.78 111.76 0)
      (effects (font (size 1.524 1.524)))
    )
    (property "Value" "C_100n_0402" (at 142.24 111.76 0)
      (effects (font (size 1.524 1.524)) hide)
    )
    (property "Footprint" "antmicro-footprints:C_0402_1005Metric" (at 147.32 102.87 0)
      (effects (font (size 1.524 1.524)) (justify left) hide)
    )
    (property "Datasheet" "https://www.murata.com/products/productdetail?partno=GRM155R61H104KE14%23" (at 142.24 107.95 0)
      (effects (font (size 1.27 1.27)) hide)
    )
    (property "Manufacturer" "Murata" (at 147.32 97.79 0)
      (effects (font (size 1.524 1.524)) (justify left) hide)
    )
    (property "MPN" "GRM155R61H104KE14D" (at 147.32 100.33 0)
      (effects (font (size 1.524 1.524)) (justify left) hide)
    )
    (property "Val" "100n" (at 144.7863 104.14 0)
      (effects (font (size 1.27 1.27)))
    )
    (property "License" "Apache-2.0" (at 162.56 130.81 0)
      (effects (font (size 1.27 1.27) (thickness 0.15)) (justify left bottom) hide)
    )
    (property "Author" "Antmicro" (at 162.56 133.35 0)
      (effects (font (size 1.27 1.27) (thickness 0.15)) (justify left bottom) hide)
    )
    (property "Voltage" "50V" (at 162.56 135.89 0)
      (effects (font (size 1.27 1.27)) (justify left bottom) hide)
    )
    (property "Dielectric" "X5R" (at 162.56 138.43 0)
      (effects (font (size 1.27 1.27)) (justify left bottom) hide)
    )
    (property "Public" "False" (at 162.56 140.97 0)
      (effects (font (size 1.27 1.27)) (justify left bottom) hide)
    )
    (pin "1")
    (pin "2")
    (instances
      (project "ecp5-dc-scm"
        (path ""
          (reference "C94") (unit 1)
        )
      )
    )
  )

  (symbol (lib_id "antmicroMemory:AS4C256M16D3") (at 196.85 48.26 0) (unit 1)
    (in_bom yes) (on_board yes) (dnp no) (fields_autoplaced)
    (property "Reference" "U10" (at 214.63 38.735 0)
      (effects (font (size 1.524 1.524)))
    )
    (property "Value" "AS4C256M16D3" (at 214.63 41.275 0)
      (effects (font (size 1.524 1.524)))
    )
    (property "Footprint" "antmicro-footprints:BGA-96_9.0x13.0mm_Layout2x3x16_P0.8mm" (at 196.85 48.26 0)
      (effects (font (size 1.524 1.524)) hide)
    )
    (property "Datasheet" "https://www.alliancememory.com/wp-content/uploads/pdf/ddr3/4GB-AS4C256M16D3.pdf" (at 196.85 48.26 0)
      (effects (font (size 1.524 1.524)) hide)
    )
    (property "Manufacturer" "Alliance Memory" (at 247.65 58.42 0)
      (effects (font (size 1.27 1.27) (thickness 0.15)) (justify left bottom) hide)
    )
    (property "MPN" "AS4C256M16D3" (at 214.63 43.815 0)
      (effects (font (size 1.27 1.27) (thickness 0.15)))
    )
    (property "Author" "Antmicro" (at 247.65 63.5 0)
      (effects (font (size 1.27 1.27) (thickness 0.15)) (justify left bottom) hide)
    )
    (property "License" "Apache-2.0" (at 247.65 66.04 0)
      (effects (font (size 1.27 1.27) (thickness 0.15)) (justify left bottom) hide)
    )
    (pin "A2")
    (pin "A3")
    (pin "A7")
    (pin "B7")
    (pin "B8")
    (pin "C2")
    (pin "C3")
    (pin "C7")
    (pin "C8")
    (pin "D3")
    (pin "D7")
    (pin "E3")
    (pin "E7")
    (pin "F2")
    (pin "F3")
    (pin "F7")
    (pin "F8")
    (pin "G2")
    (pin "G3")
    (pin "H3")
    (pin "H7")
    (pin "H8")
    (pin "J3")
    (pin "J7")
    (pin "K1")
    (pin "K3")
    (pin "K7")
    (pin "K9")
    (pin "L2")
    (pin "L3")
    (pin "L7")
    (pin "M2")
    (pin "M3")
    (pin "N2")
    (pin "N3")
    (pin "N7")
    (pin "N8")
    (pin "P2")
    (pin "P3")
    (pin "P7")
    (pin "P8")
    (pin "R2")
    (pin "R3")
    (pin "R7")
    (pin "R8")
    (pin "T2")
    (pin "T3")
    (pin "T7")
    (pin "T8")
    (pin "A1")
    (pin "A8")
    (pin "A9")
    (pin "B1")
    (pin "B2")
    (pin "B3")
    (pin "B9")
    (pin "C1")
    (pin "C9")
    (pin "D1")
    (pin "D2")
    (pin "D8")
    (pin "D9")
    (pin "E1")
    (pin "E2")
    (pin "E8")
    (pin "E9")
    (pin "F1")
    (pin "F9")
    (pin "G1")
    (pin "G7")
    (pin "G8")
    (pin "G9")
    (pin "H1")
    (pin "H2")
    (pin "H9")
    (pin "J1")
    (pin "J2")
    (pin "J8")
    (pin "J9")
    (pin "K2")
    (pin "K8")
    (pin "L1")
    (pin "L8")
    (pin "L9")
    (pin "M1")
    (pin "M7")
    (pin "M8")
    (pin "M9")
    (pin "N1")
    (pin "N9")
    (pin "P1")
    (pin "P9")
    (pin "R1")
    (pin "R9")
    (pin "T1")
    (pin "T9")
    (pin "J1")
    (pin "J9")
    (pin "L1")
    (pin "L9")
    (pin "M7")
    (pin "T7")
    (instances
      (project "ecp5-dc-scm"
        (path ""
          (reference "U10") (unit 1)
        )
      )
    )
  )

  (symbol (lib_id "antmicroCapacitors0402:C_1n_0402") (at 176.53 227.33 90) (unit 1)
    (in_bom yes) (on_board yes) (dnp no) (fields_autoplaced)
    (property "Reference" "C196" (at 179.07 223.5136 90)
      (effects (font (size 1.524 1.524)) (justify right))
    )
    (property "Value" "C_1n_0402" (at 180.34 227.33 0)
      (effects (font (size 1.524 1.524)) hide)
    )
    (property "Footprint" "antmicro-footprints:C_0402_1005Metric" (at 171.45 222.25 0)
      (effects (font (size 1.524 1.524)) (justify left) hide)
    )
    (property "Datasheet" "https://www.murata.com/products/productdetail?partno=GRM1555C1H102JA01%23" (at 176.53 227.33 0)
      (effects (font (size 1.27 1.27)) hide)
    )
    (property "Manufacturer" "Murata" (at 166.37 222.25 0)
      (effects (font (size 1.524 1.524)) (justify left) hide)
    )
    (property "MPN" "GRM1555C1H102JA01D" (at 168.91 222.25 0)
      (effects (font (size 1.524 1.524)) (justify left) hide)
    )
    (property "Val" "1n" (at 179.07 226.0536 90)
      (effects (font (size 1.27 1.27)) (justify right))
    )
    (property "License" "Apache-2.0" (at 199.39 207.01 0)
      (effects (font (size 1.27 1.27) (thickness 0.15)) (justify left bottom) hide)
    )
    (property "Author" "Antmicro" (at 201.93 207.01 0)
      (effects (font (size 1.27 1.27) (thickness 0.15)) (justify left bottom) hide)
    )
    (property "Voltage" "50V" (at 204.47 207.01 0)
      (effects (font (size 1.27 1.27)) (justify left bottom) hide)
    )
    (property "Dielectric" "C0G" (at 207.01 207.01 0)
      (effects (font (size 1.27 1.27)) (justify left bottom) hide)
    )
    (property "Public" "False" (at 209.55 207.01 0)
      (effects (font (size 1.27 1.27)) (justify left bottom) hide)
    )
    (pin "1")
    (pin "2")
    (instances
      (project "ecp5-dc-scm"
        (path ""
          (reference "C196") (unit 1)
        )
      )
    )
  )

  (symbol (lib_id "antmicropower:GND") (at 171.45 234.95 0) (unit 1)
    (in_bom yes) (on_board yes) (dnp no)
    (property "Reference" "#PWR0124" (at 171.45 241.3 0)
      (effects (font (size 1.27 1.27)) hide)
    )
    (property "Value" "GND" (at 171.577 239.3442 0)
      (effects (font (size 1.27 1.27)))
    )
    (property "Footprint" "" (at 171.45 234.95 0)
      (effects (font (size 1.27 1.27)) hide)
    )
    (property "Datasheet" "" (at 171.45 234.95 0)
      (effects (font (size 1.27 1.27)) hide)
    )
    (property "Author" "Antmicro" (at 180.34 242.57 0)
      (effects (font (size 1.27 1.27) (thickness 0.15)) (justify left bottom) hide)
    )
    (property "License" "Apache-2.0" (at 180.34 245.11 0)
      (effects (font (size 1.27 1.27) (thickness 0.15)) (justify left bottom) hide)
    )
    (pin "1")
    (instances
      (project "ecp5-dc-scm"
        (path ""
          (reference "#PWR0124") (unit 1)
        )
      )
    )
  )

  (symbol (lib_id "antmicroPMICVoltageRegulatorsDCDCSwitchingControllers:TPS51200DRCT") (at 209.55 210.82 0) (unit 1)
    (in_bom yes) (on_board yes) (dnp no)
    (property "Reference" "U11" (at 214.63 207.01 0)
      (effects (font (size 1.27 1.27) (thickness 0.15)))
    )
    (property "Value" "TPS51200DRCT" (at 245.11 218.44 0)
      (effects (font (size 1.27 1.27) (thickness 0.15)) (justify left bottom) hide)
    )
    (property "Footprint" "antmicro-footprints:VSON-10-1EP_3x3mm" (at 245.11 220.98 0)
      (effects (font (size 1.27 1.27) (thickness 0.15)) (justify left bottom) hide)
    )
    (property "Datasheet" "https://www.ti.com/lit/ds/symlink/tps51200.pdf?ts=1685420125657" (at 245.11 223.52 0)
      (effects (font (size 1.27 1.27) (thickness 0.15)) (justify left bottom) hide)
    )
    (property "MPN" "TPS51200DRCT" (at 219.71 226.06 0)
      (effects (font (size 1.27 1.27) (thickness 0.15)))
    )
    (property "Manufacturer" "Texas Instruments" (at 245.11 226.06 0)
      (effects (font (size 1.27 1.27) (thickness 0.15)) (justify left bottom) hide)
    )
    (property "Author" "Antmicro" (at 245.11 231.14 0)
      (effects (font (size 1.27 1.27) (thickness 0.15)) (justify left bottom) hide)
    )
    (property "License" "Apache-2.0" (at 245.11 233.68 0)
      (effects (font (size 1.27 1.27) (thickness 0.15)) (justify left bottom) hide)
    )
    (pin "1")
    (pin "11")
    (pin "5")
    (pin "10")
    (pin "6")
    (pin "9")
    (pin "7")
    (pin "8")
    (pin "3")
    (pin "2")
    (pin "4")
    (instances
      (project "ecp5-dc-scm"
        (path ""
          (reference "U11") (unit 1)
        )
      )
    )
  )

  (symbol (lib_id "antmicropower:GND") (at 243.84 139.7 0) (unit 1)
    (in_bom yes) (on_board yes) (dnp no)
    (property "Reference" "#PWR0132" (at 243.84 146.05 0)
      (effects (font (size 1.27 1.27)) hide)
    )
    (property "Value" "GND" (at 243.967 144.0942 0)
      (effects (font (size 1.27 1.27)))
    )
    (property "Footprint" "" (at 243.84 139.7 0)
      (effects (font (size 1.27 1.27)) hide)
    )
    (property "Datasheet" "" (at 243.84 139.7 0)
      (effects (font (size 1.27 1.27)) hide)
    )
    (property "Author" "Antmicro" (at 252.73 147.32 0)
      (effects (font (size 1.27 1.27) (thickness 0.15)) (justify left bottom) hide)
    )
    (property "License" "Apache-2.0" (at 252.73 149.86 0)
      (effects (font (size 1.27 1.27) (thickness 0.15)) (justify left bottom) hide)
    )
    (pin "1")
    (instances
      (project "ecp5-dc-scm"
        (path ""
          (reference "#PWR0132") (unit 1)
        )
      )
    )
  )

  (symbol (lib_id "antmicropower:GND") (at 234.95 139.7 0) (unit 1)
    (in_bom yes) (on_board yes) (dnp no)
    (property "Reference" "#PWR0144" (at 234.95 146.05 0)
      (effects (font (size 1.27 1.27)) hide)
    )
    (property "Value" "GND" (at 235.077 144.0942 0)
      (effects (font (size 1.27 1.27)))
    )
    (property "Footprint" "" (at 234.95 139.7 0)
      (effects (font (size 1.27 1.27)) hide)
    )
    (property "Datasheet" "" (at 234.95 139.7 0)
      (effects (font (size 1.27 1.27)) hide)
    )
    (property "Author" "Antmicro" (at 243.84 147.32 0)
      (effects (font (size 1.27 1.27) (thickness 0.15)) (justify left bottom) hide)
    )
    (property "License" "Apache-2.0" (at 243.84 149.86 0)
      (effects (font (size 1.27 1.27) (thickness 0.15)) (justify left bottom) hide)
    )
    (pin "1")
    (instances
      (project "ecp5-dc-scm"
        (path ""
          (reference "#PWR0144") (unit 1)
        )
      )
    )
  )

  (symbol (lib_id "antmicropower:GND") (at 238.76 139.7 0) (unit 1)
    (in_bom yes) (on_board yes) (dnp no)
    (property "Reference" "#PWR0143" (at 238.76 146.05 0)
      (effects (font (size 1.27 1.27)) hide)
    )
    (property "Value" "GND" (at 238.887 144.0942 0)
      (effects (font (size 1.27 1.27)))
    )
    (property "Footprint" "" (at 238.76 139.7 0)
      (effects (font (size 1.27 1.27)) hide)
    )
    (property "Datasheet" "" (at 238.76 139.7 0)
      (effects (font (size 1.27 1.27)) hide)
    )
    (property "Author" "Antmicro" (at 247.65 147.32 0)
      (effects (font (size 1.27 1.27) (thickness 0.15)) (justify left bottom) hide)
    )
    (property "License" "Apache-2.0" (at 247.65 149.86 0)
      (effects (font (size 1.27 1.27) (thickness 0.15)) (justify left bottom) hide)
    )
    (pin "1")
    (instances
      (project "ecp5-dc-scm"
        (path ""
          (reference "#PWR0143") (unit 1)
        )
      )
    )
  )
)
